FILE_TYPE = MACRO_DRAWING;
SET COLOR_WIRE YELLOW;
SET COLOR_PROP MONO;
SET COLOR_DOT WHITE;
SET COLOR_ARC YELLOW;
SET COLOR_BODY GREEN;
SET COLOR_NOTE MONO;
SET PROP_DISPLAY VALUE;
SET PAGE_NUMBER P104;
FORCEADD OFFPAGE..1
(-525 2000);
FORCEPROP 2 LAST $XR0 190 
J 0
(-777 2000);
DISPLAY 0.638298 (-777 2000);
PAINT MONO (-777 2000);
FORCEPROP 2 LAST CDS_LIB mstr_standard
J 0
(-525 2000);
PAINT ORANGE (-525 2000);
DISPLAY INVISIBLE (-525 2000);
FORCEPROP 1 LAST COMMENT_BODY TRUE
J 0
(-400 1900);
DISPLAY 0.872340 (-400 1900);
PAINT GREEN (-400 1900);
DISPLAY INVISIBLE (-400 1900);
FORCEPROP 1 LAST OFFPAGE TRUE
J 0
(-200 1875);
DISPLAY 0.872340 (-200 1875);
PAINT GREEN (-200 1875);
DISPLAY INVISIBLE (-200 1875);
FORCEPROP 2 LAST PATH I100
J 0
(-475 2075);
DISPLAY 1.021277 (-475 2075);
PAINT ORANGE (-475 2075);
DISPLAY INVISIBLE (-475 2075);
FORCEADD OFFPAGE..1
(-525 1500);
FORCEPROP 2 LAST $XR0 190 
J 0
(-777 1500);
DISPLAY 0.638298 (-777 1500);
PAINT MONO (-777 1500);
FORCEPROP 2 LAST CDS_LIB mstr_standard
J 0
(-525 1500);
PAINT ORANGE (-525 1500);
DISPLAY INVISIBLE (-525 1500);
FORCEPROP 2 LAST PATH I101
J 0
(-475 1575);
DISPLAY 1.021277 (-475 1575);
PAINT ORANGE (-475 1575);
DISPLAY INVISIBLE (-475 1575);
FORCEPROP 1 LAST COMMENT_BODY TRUE
J 0
(-400 1400);
DISPLAY 0.872340 (-400 1400);
PAINT GREEN (-400 1400);
DISPLAY INVISIBLE (-400 1400);
FORCEPROP 1 LAST OFFPAGE TRUE
J 0
(-200 1375);
DISPLAY 0.872340 (-200 1375);
PAINT GREEN (-200 1375);
DISPLAY INVISIBLE (-200 1375);
FORCEADD OFFPAGE..1
(-525 1300);
FORCEPROP 2 LAST $XR0 191 
J 0
(-777 1300);
DISPLAY 0.638298 (-777 1300);
PAINT MONO (-777 1300);
FORCEPROP 2 LAST CDS_LIB mstr_standard
J 0
(-525 1300);
PAINT ORANGE (-525 1300);
DISPLAY INVISIBLE (-525 1300);
FORCEPROP 2 LAST PATH I102
J 0
(-475 1375);
DISPLAY 1.021277 (-475 1375);
PAINT ORANGE (-475 1375);
DISPLAY INVISIBLE (-475 1375);
FORCEPROP 1 LAST COMMENT_BODY TRUE
J 0
(-400 1200);
DISPLAY 0.872340 (-400 1200);
PAINT GREEN (-400 1200);
DISPLAY INVISIBLE (-400 1200);
FORCEPROP 1 LAST OFFPAGE TRUE
J 0
(-200 1175);
DISPLAY 0.872340 (-200 1175);
PAINT GREEN (-200 1175);
DISPLAY INVISIBLE (-200 1175);
FORCEADD P3V3..1
(-3975 5350);
FORCEPROP 3 LASTPIN (-3975 5300) SIG_NAME P3V3\g
J 0
(-3965 5310);
DISPLAY 0.659574 (-3965 5310);
PAINT MONO (-3965 5310);
DISPLAY INVISIBLE (-3965 5310);
FORCEPROP 1 LAST HDL_POWER P3V3
J 0
(-4300 5225);
DISPLAY 0.872340 (-4300 5225);
PAINT ORANGE (-4300 5225);
DISPLAY INVISIBLE (-4300 5225);
FORCEPROP 1 LAST BODY_TYPE PLUMBING
J 0
(-4020 5307);
DISPLAY 0.340426 (-4020 5307);
PAINT GREEN (-4020 5307);
DISPLAY INVISIBLE (-4020 5307);
FORCEPROP 1 LAST VOLTAGE 3.3V
J 0
(-4020 5307);
DISPLAY 0.340426 (-4020 5307);
PAINT SKYBLUE (-4020 5307);
DISPLAY INVISIBLE (-4020 5307);
FORCEPROP 1 LAST PATH I24
J 0
(-3930 5352);
DISPLAY 0.340426 (-3930 5352);
PAINT GREEN (-3930 5352);
DISPLAY INVISIBLE (-3930 5352);
FORCEPROP 2 LAST CDS_LIB mstr_symbols
J 0
(-3975 5350);
PAINT ORANGE (-3975 5350);
DISPLAY INVISIBLE (-3975 5350);
FORCEPROP 1 LAST SIZE 1B
J 0
(-3930 5372);
DISPLAY 0.340426 (-3930 5372);
PAINT GREEN (-3930 5372);
DISPLAY INVISIBLE (-3930 5372);
FORCEADD CAP_A..1
(-4250 5100);
FORCEPROP 1 LASTPIN (-4250 5000) $PN 2
J 0
(-4240 4980);
DISPLAY 0.617021 (-4240 4980);
PAINT ORANGE (-4240 4980);
FORCEPROP 1 LAST TOLERANCE 10%
J 0
(-4200 5050);
DISPLAY 0.617021 (-4200 5050);
PAINT SKYBLUE (-4200 5050);
FORCEPROP 1 LAST MATERIAL X7R
J 0
(-4200 5000);
DISPLAY 0.617021 (-4200 5000);
PAINT SKYBLUE (-4200 5000);
FORCEPROP 1 LAST VOLTAGE 16V
J 0
(-4200 5100);
DISPLAY 0.617021 (-4200 5100);
PAINT SKYBLUE (-4200 5100);
FORCEPROP 1 LASTPIN (-4250 5200) $PN 1
J 0
(-4240 5180);
DISPLAY 0.617021 (-4240 5180);
PAINT ORANGE (-4240 5180);
FORCEPROP 1 LAST LOCATION C6F1
J 0
(-4200 5200);
DISPLAY 0.617021 (-4200 5200);
PAINT AQUA (-4200 5200);
FORCEPROP 1 LAST PART_NUMBER A36096-030
J 0
(-4200 4950);
DISPLAY 0.617021 (-4200 4950);
PAINT BLUE (-4200 4950);
FORCEPROP 1 LAST PACK_TYPE 0402V
J 0
(-4200 4900);
DISPLAY 0.617021 (-4200 4900);
PAINT SKYBLUE (-4200 4900);
FORCEPROP 1 LAST VALUE 0.1UF
J 0
(-4200 5150);
DISPLAY 0.617021 (-4200 5150);
PAINT SKYBLUE (-4200 5150);
FORCEPROP 2 LAST CDS_LIB dev_discrete
J 0
(-4250 5100);
PAINT ORANGE (-4250 5100);
DISPLAY INVISIBLE (-4250 5100);
FORCEPROP 1 LAST PATH I25
J 0
(-4200 5250);
DISPLAY 0.978723 (-4200 5250);
PAINT WHITE (-4200 5250);
DISPLAY INVISIBLE (-4200 5250);
FORCEPROP 0 LAST ROOM CLOCK_CPU0_OSC
J 0
(-4200 5300);
DISPLAY 1.021277 (-4200 5300);
PAINT ORANGE (-4200 5300);
DISPLAY INVISIBLE (-4200 5300);
FORCEPROP 2 LAST CDS_SEC 1
J 0
(-4200 5250);
PAINT ORANGE (-4200 5250);
DISPLAY INVISIBLE (-4200 5250);
FORCEPROP 2 LAST SEC_TYPE 0402V
J 0
(-4200 5300);
DISPLAY 1.021277 (-4200 5300);
PAINT ORANGE (-4200 5300);
DISPLAY INVISIBLE (-4200 5300);
FORCEPROP 2 LAST SEC 1
J 0
(-4200 5300);
DISPLAY 0.680851 (-4200 5300);
PAINT MONO (-4200 5300);
DISPLAY INVISIBLE (-4200 5300);
FORCEPROP 2 LAST CDS_LOCATION C6F1
J 0
(-4200 5200);
DISPLAY 0.617021 (-4200 5200);
PAINT AQUA (-4200 5200);
DISPLAY INVISIBLE (-4200 5200);
FORCEADD GND..1
(-2725 4550);
FORCEPROP 3 LASTPIN (-2725 4600) SIG_NAME GND\g
J 0
(-2715 4610);
DISPLAY 0.659574 (-2715 4610);
PAINT MONO (-2715 4610);
DISPLAY INVISIBLE (-2715 4610);
FORCEPROP 1 LAST SIZE 1B
J 0
(-2650 4500);
DISPLAY 0.872340 (-2650 4500);
PAINT AQUA (-2650 4500);
DISPLAY INVISIBLE (-2650 4500);
FORCEPROP 1 LAST BODY_TYPE PLUMBING
J 0
(-2770 4507);
DISPLAY 0.340426 (-2770 4507);
PAINT GREEN (-2770 4507);
DISPLAY INVISIBLE (-2770 4507);
FORCEPROP 2 LAST CDS_LIB mstr_symbols
J 0
(-2725 4550);
PAINT ORANGE (-2725 4550);
DISPLAY INVISIBLE (-2725 4550);
FORCEPROP 1 LAST VOLTAGE 0.0V
J 0
(-2770 4507);
DISPLAY 0.340426 (-2770 4507);
PAINT SKYBLUE (-2770 4507);
DISPLAY INVISIBLE (-2770 4507);
FORCEPROP 1 LAST PATH I26
J 0
(-2650 4550);
DISPLAY 0.872340 (-2650 4550);
PAINT AQUA (-2650 4550);
DISPLAY INVISIBLE (-2650 4550);
FORCEPROP 1 LAST HDL_POWER GND
J 0
(-2725 4700);
DISPLAY 0.872340 (-2725 4700);
PAINT GREEN (-2725 4700);
DISPLAY INVISIBLE (-2725 4700);
FORCEADD GND..1
(-4250 4900);
FORCEPROP 3 LASTPIN (-4250 4950) SIG_NAME GND\g
J 0
(-4240 4960);
DISPLAY 0.659574 (-4240 4960);
PAINT MONO (-4240 4960);
DISPLAY INVISIBLE (-4240 4960);
FORCEPROP 1 LAST SIZE 1B
J 0
(-4175 4850);
DISPLAY 0.872340 (-4175 4850);
PAINT AQUA (-4175 4850);
DISPLAY INVISIBLE (-4175 4850);
FORCEPROP 1 LAST BODY_TYPE PLUMBING
J 0
(-4295 4857);
DISPLAY 0.340426 (-4295 4857);
PAINT GREEN (-4295 4857);
DISPLAY INVISIBLE (-4295 4857);
FORCEPROP 1 LAST VOLTAGE 0.0V
J 0
(-4295 4857);
DISPLAY 0.340426 (-4295 4857);
PAINT SKYBLUE (-4295 4857);
DISPLAY INVISIBLE (-4295 4857);
FORCEPROP 2 LAST CDS_LIB mstr_symbols
J 0
(-4250 4900);
PAINT ORANGE (-4250 4900);
DISPLAY INVISIBLE (-4250 4900);
FORCEPROP 1 LAST HDL_POWER GND
J 0
(-4250 5050);
DISPLAY 0.872340 (-4250 5050);
PAINT GREEN (-4250 5050);
DISPLAY INVISIBLE (-4250 5050);
FORCEPROP 1 LAST PATH I27
J 0
(-4175 4900);
DISPLAY 0.872340 (-4175 4900);
PAINT AQUA (-4175 4900);
DISPLAY INVISIBLE (-4175 4900);
FORCEADD OFFPAGE..1
(-4525 4775);
FORCEPROP 2 LAST $XR0 104 
J 0
(-4777 4775);
DISPLAY 0.638298 (-4777 4775);
PAINT MONO (-4777 4775);
FORCEPROP 1 LAST COMMENT_BODY TRUE
J 0
(-4400 4675);
DISPLAY 0.872340 (-4400 4675);
PAINT GREEN (-4400 4675);
DISPLAY INVISIBLE (-4400 4675);
FORCEPROP 2 LAST PATH I29
J 0
(-4475 4850);
DISPLAY 1.021277 (-4475 4850);
PAINT ORANGE (-4475 4850);
DISPLAY INVISIBLE (-4475 4850);
FORCEPROP 2 LAST CDS_LIB mstr_standard
J 0
(-4525 4775);
PAINT ORANGE (-4525 4775);
DISPLAY INVISIBLE (-4525 4775);
FORCEPROP 1 LAST OFFPAGE TRUE
J 0
(-4200 4650);
DISPLAY 0.872340 (-4200 4650);
PAINT GREEN (-4200 4650);
DISPLAY INVISIBLE (-4200 4650);
FORCEADD GND..1
(-3050 3700);
FORCEPROP 3 LASTPIN (-3050 3750) SIG_NAME GND\g
J 0
(-3040 3760);
DISPLAY 0.659574 (-3040 3760);
PAINT MONO (-3040 3760);
DISPLAY INVISIBLE (-3040 3760);
FORCEPROP 1 LAST VOLTAGE 0.0V
J 0
(-3095 3657);
DISPLAY 0.340426 (-3095 3657);
PAINT SKYBLUE (-3095 3657);
DISPLAY INVISIBLE (-3095 3657);
FORCEPROP 1 LAST BODY_TYPE PLUMBING
J 0
(-3095 3657);
DISPLAY 0.340426 (-3095 3657);
PAINT GREEN (-3095 3657);
DISPLAY INVISIBLE (-3095 3657);
FORCEPROP 2 LAST CDS_LIB mstr_symbols
J 0
(-3050 3700);
PAINT ORANGE (-3050 3700);
DISPLAY INVISIBLE (-3050 3700);
FORCEPROP 1 LAST PATH I31
J 0
(-2975 3700);
DISPLAY 0.872340 (-2975 3700);
PAINT AQUA (-2975 3700);
DISPLAY INVISIBLE (-2975 3700);
FORCEPROP 1 LAST SIZE 1B
J 0
(-2975 3650);
DISPLAY 0.872340 (-2975 3650);
PAINT AQUA (-2975 3650);
DISPLAY INVISIBLE (-2975 3650);
FORCEPROP 1 LAST HDL_POWER GND
J 0
(-3050 3850);
DISPLAY 0.872340 (-3050 3850);
PAINT GREEN (-3050 3850);
DISPLAY INVISIBLE (-3050 3850);
FORCEADD P3V3..1
(-4275 4475);
FORCEPROP 3 LASTPIN (-4275 4425) SIG_NAME P3V3\g
J 0
(-4265 4435);
DISPLAY 0.659574 (-4265 4435);
PAINT MONO (-4265 4435);
DISPLAY INVISIBLE (-4265 4435);
FORCEPROP 1 LAST HDL_POWER P3V3
J 0
(-4600 4350);
DISPLAY 0.872340 (-4600 4350);
PAINT ORANGE (-4600 4350);
DISPLAY INVISIBLE (-4600 4350);
FORCEPROP 1 LAST BODY_TYPE PLUMBING
J 0
(-4320 4432);
DISPLAY 0.340426 (-4320 4432);
PAINT GREEN (-4320 4432);
DISPLAY INVISIBLE (-4320 4432);
FORCEPROP 1 LAST VOLTAGE 3.3V
J 0
(-4320 4432);
DISPLAY 0.340426 (-4320 4432);
PAINT SKYBLUE (-4320 4432);
DISPLAY INVISIBLE (-4320 4432);
FORCEPROP 2 LAST CDS_LIB mstr_symbols
J 0
(-4275 4475);
PAINT ORANGE (-4275 4475);
DISPLAY INVISIBLE (-4275 4475);
FORCEPROP 1 LAST PATH I32
J 0
(-4230 4477);
DISPLAY 0.340426 (-4230 4477);
PAINT GREEN (-4230 4477);
DISPLAY INVISIBLE (-4230 4477);
FORCEPROP 1 LAST SIZE 1B
J 0
(-4230 4497);
DISPLAY 0.340426 (-4230 4497);
PAINT GREEN (-4230 4497);
DISPLAY INVISIBLE (-4230 4497);
FORCEADD GND..1
(-4575 4025);
FORCEPROP 3 LASTPIN (-4575 4075) SIG_NAME GND\g
J 0
(-4565 4085);
DISPLAY 0.659574 (-4565 4085);
PAINT MONO (-4565 4085);
DISPLAY INVISIBLE (-4565 4085);
FORCEPROP 1 LAST BODY_TYPE PLUMBING
J 0
(-4620 3982);
DISPLAY 0.340426 (-4620 3982);
PAINT GREEN (-4620 3982);
DISPLAY INVISIBLE (-4620 3982);
FORCEPROP 1 LAST VOLTAGE 0.0V
J 0
(-4620 3982);
DISPLAY 0.340426 (-4620 3982);
PAINT SKYBLUE (-4620 3982);
DISPLAY INVISIBLE (-4620 3982);
FORCEPROP 2 LAST CDS_LIB mstr_symbols
J 0
(-4575 4025);
PAINT ORANGE (-4575 4025);
DISPLAY INVISIBLE (-4575 4025);
FORCEPROP 1 LAST SIZE 1B
J 0
(-4500 3975);
DISPLAY 0.872340 (-4500 3975);
PAINT AQUA (-4500 3975);
DISPLAY INVISIBLE (-4500 3975);
FORCEPROP 1 LAST PATH I33
J 0
(-4500 4025);
DISPLAY 0.872340 (-4500 4025);
PAINT AQUA (-4500 4025);
DISPLAY INVISIBLE (-4500 4025);
FORCEPROP 1 LAST HDL_POWER GND
J 0
(-4575 4175);
DISPLAY 0.872340 (-4575 4175);
PAINT GREEN (-4575 4175);
DISPLAY INVISIBLE (-4575 4175);
FORCEADD CAP_A..1
(-4575 4225);
FORCEPROP 1 LAST PACK_TYPE 0402V
J 0
(-4525 4025);
DISPLAY 0.617021 (-4525 4025);
PAINT SKYBLUE (-4525 4025);
FORCEPROP 1 LAST PART_NUMBER A36096-030
J 0
(-4525 4075);
DISPLAY 0.617021 (-4525 4075);
PAINT BLUE (-4525 4075);
FORCEPROP 1 LASTPIN (-4575 4325) $PN 1
J 0
(-4565 4305);
DISPLAY 0.617021 (-4565 4305);
PAINT ORANGE (-4565 4305);
FORCEPROP 1 LASTPIN (-4575 4125) $PN 2
J 0
(-4565 4105);
DISPLAY 0.617021 (-4565 4105);
PAINT ORANGE (-4565 4105);
FORCEPROP 1 LAST MATERIAL X7R
J 0
(-4525 4125);
DISPLAY 0.617021 (-4525 4125);
PAINT SKYBLUE (-4525 4125);
FORCEPROP 1 LAST TOLERANCE 10%
J 0
(-4525 4175);
DISPLAY 0.617021 (-4525 4175);
PAINT SKYBLUE (-4525 4175);
FORCEPROP 1 LAST VALUE 0.1UF
J 0
(-4525 4275);
DISPLAY 0.617021 (-4525 4275);
PAINT SKYBLUE (-4525 4275);
FORCEPROP 1 LAST LOCATION C3F2
J 0
(-4525 4325);
DISPLAY 0.617021 (-4525 4325);
PAINT AQUA (-4525 4325);
FORCEPROP 1 LAST VOLTAGE 16V
J 0
(-4525 4225);
DISPLAY 0.617021 (-4525 4225);
PAINT SKYBLUE (-4525 4225);
FORCEPROP 2 LAST CDS_LOCATION C3F2
J 0
(-4525 4325);
DISPLAY 0.617021 (-4525 4325);
PAINT AQUA (-4525 4325);
DISPLAY INVISIBLE (-4525 4325);
FORCEPROP 2 LAST CDS_LIB dev_discrete
J 0
(-4575 4225);
PAINT ORANGE (-4575 4225);
DISPLAY INVISIBLE (-4575 4225);
FORCEPROP 1 LAST PATH I34
J 0
(-4525 4375);
DISPLAY 0.978723 (-4525 4375);
PAINT WHITE (-4525 4375);
DISPLAY INVISIBLE (-4525 4375);
FORCEPROP 0 LAST ROOM CLOCK_CPU1_OSC
J 0
(-4525 4425);
DISPLAY 1.021277 (-4525 4425);
PAINT ORANGE (-4525 4425);
DISPLAY INVISIBLE (-4525 4425);
FORCEPROP 2 LAST SEC_TYPE 0402V
J 0
(-4525 4425);
DISPLAY 1.021277 (-4525 4425);
PAINT ORANGE (-4525 4425);
DISPLAY INVISIBLE (-4525 4425);
FORCEPROP 2 LAST SEC 1
J 0
(-4525 4425);
DISPLAY 0.680851 (-4525 4425);
PAINT MONO (-4525 4425);
DISPLAY INVISIBLE (-4525 4425);
FORCEPROP 2 LAST CDS_SEC 1
J 0
(-4525 4375);
PAINT ORANGE (-4525 4375);
DISPLAY INVISIBLE (-4525 4375);
FORCEADD OFFPAGE..1
(-4850 3925);
FORCEPROP 2 LAST $XR0 104 
J 0
(-5102 3925);
DISPLAY 0.638298 (-5102 3925);
PAINT MONO (-5102 3925);
FORCEPROP 1 LAST COMMENT_BODY TRUE
J 0
(-4725 3825);
DISPLAY 0.872340 (-4725 3825);
PAINT GREEN (-4725 3825);
DISPLAY INVISIBLE (-4725 3825);
FORCEPROP 2 LAST PATH I36
J 0
(-4800 4000);
DISPLAY 1.021277 (-4800 4000);
PAINT ORANGE (-4800 4000);
DISPLAY INVISIBLE (-4800 4000);
FORCEPROP 2 LAST CDS_LIB mstr_standard
J 0
(-4850 3925);
PAINT ORANGE (-4850 3925);
DISPLAY INVISIBLE (-4850 3925);
FORCEPROP 1 LAST OFFPAGE TRUE
J 0
(-4525 3800);
DISPLAY 0.872340 (-4525 3800);
PAINT GREEN (-4525 3800);
DISPLAY INVISIBLE (-4525 3800);
FORCEADD RES..1
(525 4300);
FORCEPROP 1 LAST VALUE 0.0
J 1
(300 4250);
DISPLAY 0.617021 (300 4250);
PAINT SKYBLUE (300 4250);
FORCEPROP 1 LAST WATTAGE 1/16W
J 0
(350 4250);
DISPLAY 0.617021 (350 4250);
PAINT SKYBLUE (350 4250);
FORCEPROP 1 LASTPIN (425 4300) $PN 1
J 0
(437 4312);
DISPLAY 0.617021 (437 4312);
PAINT ORANGE (437 4312);
FORCEPROP 1 LAST LOCATION R6F8
J 0
(475 4350);
DISPLAY 0.617021 (475 4350);
PAINT AQUA (475 4350);
FORCEPROP 1 LAST TOLERANCE 5%
J 0
(500 4250);
DISPLAY 0.617021 (500 4250);
PAINT SKYBLUE (500 4250);
FORCEPROP 1 LASTPIN (625 4300) $PN 2
J 0
(587 4312);
DISPLAY 0.617021 (587 4312);
PAINT ORANGE (587 4312);
FORCEPROP 1 LAST MATERIAL EMPTY
J 1
(650 4250);
DISPLAY 0.617021 (650 4250);
PAINT RED (650 4250);
FORCEPROP 1 LAST PACK_TYPE 0402
J 0
(725 4250);
DISPLAY 0.617021 (725 4250);
PAINT SKYBLUE (725 4250);
FORCEPROP 1 LAST PART_NUMBER G21497-005
J 0
(650 4300);
DISPLAY 0.617021 (650 4300);
PAINT BLUE (650 4300);
FORCEPROP 2 LAST CDS_LOCATION R6F8
J 0
(475 4350);
DISPLAY 0.617021 (475 4350);
PAINT AQUA (475 4350);
DISPLAY INVISIBLE (475 4350);
FORCEPROP 2 LAST SEC_TYPE 0402
J 0
(475 4500);
DISPLAY 1.021277 (475 4500);
PAINT ORANGE (475 4500);
DISPLAY INVISIBLE (475 4500);
FORCEPROP 2 LAST SEC 1
J 0
(475 4500);
DISPLAY 0.680851 (475 4500);
PAINT MONO (475 4500);
DISPLAY INVISIBLE (475 4500);
FORCEPROP 1 LAST PATH I37
J 0
(475 4450);
DISPLAY 0.978723 (475 4450);
PAINT WHITE (475 4450);
DISPLAY INVISIBLE (475 4450);
FORCEPROP 0 LAST NO_XNET_CONNECTION 1
J 0
(475 4500);
PAINT MONO (475 4500);
DISPLAY INVISIBLE (475 4500);
FORCEPROP 2 LAST CDS_LIB mstr_discrete
J 0
(525 4300);
PAINT ORANGE (525 4300);
DISPLAY INVISIBLE (525 4300);
FORCEPROP 2 LAST ROOM CLOCK_CPU0_OSC
J 0
(1000 4400);
DISPLAY 1.021277 (1000 4400);
PAINT ORANGE (1000 4400);
DISPLAY INVISIBLE (1000 4400);
FORCEADD OFFPAGE..2
(1675 5150);
FORCEPROP 2 LAST $XR0 29 
J 0
(1864 5150);
DISPLAY 0.638298 (1864 5150);
PAINT MONO (1864 5150);
FORCEPROP 1 LAST COMMENT_BODY TRUE
J 0
(1630 5055);
DISPLAY 0.872340 (1630 5055);
PAINT GREEN (1630 5055);
DISPLAY INVISIBLE (1630 5055);
FORCEPROP 1 LAST OFFPAGE TRUE
J 0
(2000 5025);
DISPLAY 0.872340 (2000 5025);
PAINT GREEN (2000 5025);
DISPLAY INVISIBLE (2000 5025);
FORCEPROP 2 LAST CDS_LIB mstr_standard
J 0
(1675 5150);
PAINT ORANGE (1675 5150);
DISPLAY INVISIBLE (1675 5150);
FORCEPROP 2 LAST PATH I38
J 0
(1850 5225);
DISPLAY 1.021277 (1850 5225);
PAINT ORANGE (1850 5225);
DISPLAY INVISIBLE (1850 5225);
FORCEADD RES..1
(525 4950);
FORCEPROP 1 LAST VALUE 0.0
J 1
(300 4900);
DISPLAY 0.617021 (300 4900);
PAINT SKYBLUE (300 4900);
FORCEPROP 1 LAST WATTAGE 1/16W
J 0
(350 4900);
DISPLAY 0.617021 (350 4900);
PAINT SKYBLUE (350 4900);
FORCEPROP 1 LASTPIN (425 4950) $PN 1
J 0
(437 4962);
DISPLAY 0.617021 (437 4962);
PAINT ORANGE (437 4962);
FORCEPROP 1 LAST TOLERANCE 5%
J 0
(500 4900);
DISPLAY 0.617021 (500 4900);
PAINT SKYBLUE (500 4900);
FORCEPROP 1 LAST LOCATION R6F6
J 0
(475 5000);
DISPLAY 0.617021 (475 5000);
PAINT AQUA (475 5000);
FORCEPROP 1 LASTPIN (625 4950) $PN 2
J 0
(587 4962);
DISPLAY 0.617021 (587 4962);
PAINT ORANGE (587 4962);
FORCEPROP 1 LAST MATERIAL EMPTY
J 1
(650 4900);
DISPLAY 0.617021 (650 4900);
PAINT RED (650 4900);
FORCEPROP 1 LAST PACK_TYPE 0402
J 0
(725 4900);
DISPLAY 0.617021 (725 4900);
PAINT SKYBLUE (725 4900);
FORCEPROP 1 LAST PART_NUMBER G21497-005
J 0
(675 4950);
DISPLAY 0.617021 (675 4950);
PAINT BLUE (675 4950);
FORCEPROP 2 LAST CDS_LOCATION R6F6
J 0
(475 5000);
DISPLAY 0.617021 (475 5000);
PAINT AQUA (475 5000);
DISPLAY INVISIBLE (475 5000);
FORCEPROP 2 LAST CDS_LIB mstr_discrete
J 0
(525 4950);
PAINT ORANGE (525 4950);
DISPLAY INVISIBLE (525 4950);
FORCEPROP 2 LAST ROOM CLOCK_CPU0_OSC
J 0
(1000 5050);
DISPLAY 1.021277 (1000 5050);
PAINT ORANGE (1000 5050);
DISPLAY INVISIBLE (1000 5050);
FORCEPROP 1 LAST PATH I41
J 0
(475 5100);
DISPLAY 0.978723 (475 5100);
PAINT WHITE (475 5100);
DISPLAY INVISIBLE (475 5100);
FORCEPROP 0 LAST NO_XNET_CONNECTION 1
J 0
(475 5150);
PAINT MONO (475 5150);
DISPLAY INVISIBLE (475 5150);
FORCEPROP 2 LAST SEC 1
J 0
(475 5150);
DISPLAY 0.680851 (475 5150);
PAINT MONO (475 5150);
DISPLAY INVISIBLE (475 5150);
FORCEPROP 2 LAST SEC_TYPE 0402
J 0
(475 5150);
DISPLAY 1.021277 (475 5150);
PAINT ORANGE (475 5150);
DISPLAY INVISIBLE (475 5150);
FORCEADD OFFPAGE..1
(-550 5150);
FORCEPROP 2 LAST $XR0 104 
J 0
(-802 5150);
DISPLAY 0.638298 (-802 5150);
PAINT MONO (-802 5150);
FORCEPROP 1 LAST OFFPAGE TRUE
J 0
(-225 5025);
DISPLAY 0.872340 (-225 5025);
PAINT GREEN (-225 5025);
DISPLAY INVISIBLE (-225 5025);
FORCEPROP 1 LAST COMMENT_BODY TRUE
J 0
(-425 5050);
DISPLAY 0.872340 (-425 5050);
PAINT GREEN (-425 5050);
DISPLAY INVISIBLE (-425 5050);
FORCEPROP 2 LAST CDS_LIB mstr_standard
J 0
(-550 5150);
PAINT ORANGE (-550 5150);
DISPLAY INVISIBLE (-550 5150);
FORCEPROP 2 LAST PATH I42
J 0
(-500 5225);
DISPLAY 1.021277 (-500 5225);
PAINT ORANGE (-500 5225);
DISPLAY INVISIBLE (-500 5225);
FORCEADD OFFPAGE..2
(1675 4500);
FORCEPROP 2 LAST $XR0 29 
J 0
(1864 4500);
DISPLAY 0.638298 (1864 4500);
PAINT MONO (1864 4500);
FORCEPROP 1 LAST COMMENT_BODY TRUE
J 0
(1630 4405);
DISPLAY 0.872340 (1630 4405);
PAINT GREEN (1630 4405);
DISPLAY INVISIBLE (1630 4405);
FORCEPROP 2 LAST CDS_LIB mstr_standard
J 0
(1675 4500);
PAINT ORANGE (1675 4500);
DISPLAY INVISIBLE (1675 4500);
FORCEPROP 1 LAST OFFPAGE TRUE
J 0
(2000 4375);
DISPLAY 0.872340 (2000 4375);
PAINT GREEN (2000 4375);
DISPLAY INVISIBLE (2000 4375);
FORCEPROP 2 LAST PATH I44
J 0
(1850 4575);
DISPLAY 1.021277 (1850 4575);
PAINT ORANGE (1850 4575);
DISPLAY INVISIBLE (1850 4575);
FORCEADD OFFPAGE..2
(1675 3775);
FORCEPROP 2 LAST $XR0 63 
J 0
(1864 3775);
DISPLAY 0.638298 (1864 3775);
PAINT MONO (1864 3775);
FORCEPROP 1 LAST COMMENT_BODY TRUE
J 0
(1630 3680);
DISPLAY 0.872340 (1630 3680);
PAINT GREEN (1630 3680);
DISPLAY INVISIBLE (1630 3680);
FORCEPROP 2 LAST CDS_LIB mstr_standard
J 0
(1675 3775);
PAINT ORANGE (1675 3775);
DISPLAY INVISIBLE (1675 3775);
FORCEPROP 2 LAST PATH I46
J 0
(1850 3850);
DISPLAY 1.021277 (1850 3850);
PAINT ORANGE (1850 3850);
DISPLAY INVISIBLE (1850 3850);
FORCEPROP 1 LAST OFFPAGE TRUE
J 0
(2000 3650);
DISPLAY 0.872340 (2000 3650);
PAINT GREEN (2000 3650);
DISPLAY INVISIBLE (2000 3650);
FORCEADD OFFPAGE..2
(1675 3075);
FORCEPROP 2 LAST $XR0 63 
J 0
(1864 3075);
DISPLAY 0.638298 (1864 3075);
PAINT MONO (1864 3075);
FORCEPROP 1 LAST COMMENT_BODY TRUE
J 0
(1630 2980);
DISPLAY 0.872340 (1630 2980);
PAINT GREEN (1630 2980);
DISPLAY INVISIBLE (1630 2980);
FORCEPROP 1 LAST OFFPAGE TRUE
J 0
(2000 2950);
DISPLAY 0.872340 (2000 2950);
PAINT GREEN (2000 2950);
DISPLAY INVISIBLE (2000 2950);
FORCEPROP 2 LAST CDS_LIB mstr_standard
J 0
(1675 3075);
PAINT ORANGE (1675 3075);
DISPLAY INVISIBLE (1675 3075);
FORCEPROP 2 LAST PATH I48
J 0
(1850 3150);
DISPLAY 1.021277 (1850 3150);
PAINT ORANGE (1850 3150);
DISPLAY INVISIBLE (1850 3150);
FORCEADD RES..1
(525 3575);
FORCEPROP 1 LAST VALUE 0.0
J 1
(300 3525);
DISPLAY 0.617021 (300 3525);
PAINT SKYBLUE (300 3525);
FORCEPROP 1 LAST WATTAGE 1/16W
J 0
(350 3525);
DISPLAY 0.617021 (350 3525);
PAINT SKYBLUE (350 3525);
FORCEPROP 1 LASTPIN (425 3575) $PN 1
J 0
(437 3587);
DISPLAY 0.617021 (437 3587);
PAINT ORANGE (437 3587);
FORCEPROP 1 LAST TOLERANCE 5%
J 0
(500 3525);
DISPLAY 0.617021 (500 3525);
PAINT SKYBLUE (500 3525);
FORCEPROP 1 LAST LOCATION R3F1
J 0
(475 3625);
DISPLAY 0.617021 (475 3625);
PAINT AQUA (475 3625);
FORCEPROP 1 LAST MATERIAL EMPTY
J 1
(650 3525);
DISPLAY 0.617021 (650 3525);
PAINT RED (650 3525);
FORCEPROP 1 LAST PACK_TYPE 0402
J 1
(775 3525);
DISPLAY 0.617021 (775 3525);
PAINT SKYBLUE (775 3525);
FORCEPROP 1 LAST PART_NUMBER G21497-005
J 0
(650 3575);
DISPLAY 0.617021 (650 3575);
PAINT BLUE (650 3575);
FORCEPROP 1 LASTPIN (625 3575) $PN 2
J 0
(587 3587);
DISPLAY 0.617021 (587 3587);
PAINT ORANGE (587 3587);
FORCEPROP 2 LAST CDS_LOCATION R3F1
J 0
(475 3625);
DISPLAY 0.617021 (475 3625);
PAINT AQUA (475 3625);
DISPLAY INVISIBLE (475 3625);
FORCEPROP 1 LAST PATH I51
J 0
(475 3725);
DISPLAY 0.978723 (475 3725);
PAINT WHITE (475 3725);
DISPLAY INVISIBLE (475 3725);
FORCEPROP 2 LAST SEC 1
J 0
(475 3775);
DISPLAY 0.680851 (475 3775);
PAINT MONO (475 3775);
DISPLAY INVISIBLE (475 3775);
FORCEPROP 0 LAST NO_XNET_CONNECTION 1
J 0
(475 3775);
PAINT MONO (475 3775);
DISPLAY INVISIBLE (475 3775);
FORCEPROP 2 LAST SEC_TYPE 0402
J 0
(475 3775);
DISPLAY 1.021277 (475 3775);
PAINT ORANGE (475 3775);
DISPLAY INVISIBLE (475 3775);
FORCEPROP 2 LAST CDS_LIB mstr_discrete
J 0
(525 3575);
PAINT ORANGE (525 3575);
DISPLAY INVISIBLE (525 3575);
FORCEPROP 2 LAST ROOM CLOCK_CPU1_OSC
J 0
(1000 3675);
DISPLAY 1.021277 (1000 3675);
PAINT ORANGE (1000 3675);
DISPLAY INVISIBLE (1000 3675);
FORCEADD RES..1
(525 2875);
FORCEPROP 1 LAST VALUE 0.0
J 1
(300 2825);
DISPLAY 0.617021 (300 2825);
PAINT SKYBLUE (300 2825);
FORCEPROP 1 LAST WATTAGE 1/16W
J 0
(350 2825);
DISPLAY 0.617021 (350 2825);
PAINT SKYBLUE (350 2825);
FORCEPROP 1 LASTPIN (425 2875) $PN 1
J 0
(437 2887);
DISPLAY 0.617021 (437 2887);
PAINT ORANGE (437 2887);
FORCEPROP 1 LAST TOLERANCE 5%
J 0
(500 2825);
DISPLAY 0.617021 (500 2825);
PAINT SKYBLUE (500 2825);
FORCEPROP 1 LAST LOCATION R3F3
J 0
(475 2925);
DISPLAY 0.617021 (475 2925);
PAINT AQUA (475 2925);
FORCEPROP 1 LASTPIN (625 2875) $PN 2
J 0
(587 2887);
DISPLAY 0.617021 (587 2887);
PAINT ORANGE (587 2887);
FORCEPROP 1 LAST MATERIAL EMPTY
J 1
(650 2825);
DISPLAY 0.617021 (650 2825);
PAINT RED (650 2825);
FORCEPROP 1 LAST PACK_TYPE 0402
J 1
(775 2825);
DISPLAY 0.617021 (775 2825);
PAINT SKYBLUE (775 2825);
FORCEPROP 1 LAST PART_NUMBER G21497-005
J 0
(650 2875);
DISPLAY 0.617021 (650 2875);
PAINT BLUE (650 2875);
FORCEPROP 2 LAST CDS_LOCATION R3F3
J 0
(475 2925);
DISPLAY 0.617021 (475 2925);
PAINT AQUA (475 2925);
DISPLAY INVISIBLE (475 2925);
FORCEPROP 1 LAST PATH I53
J 0
(475 3025);
DISPLAY 0.978723 (475 3025);
PAINT WHITE (475 3025);
DISPLAY INVISIBLE (475 3025);
FORCEPROP 2 LAST CDS_LIB mstr_discrete
J 0
(525 2875);
PAINT ORANGE (525 2875);
DISPLAY INVISIBLE (525 2875);
FORCEPROP 2 LAST ROOM CLOCK_CPU1_OSC
J 0
(1000 2975);
DISPLAY 1.021277 (1000 2975);
PAINT ORANGE (1000 2975);
DISPLAY INVISIBLE (1000 2975);
FORCEPROP 0 LAST NO_XNET_CONNECTION 1
J 0
(475 3075);
PAINT MONO (475 3075);
DISPLAY INVISIBLE (475 3075);
FORCEPROP 2 LAST SEC 1
J 0
(475 3075);
DISPLAY 0.680851 (475 3075);
PAINT MONO (475 3075);
DISPLAY INVISIBLE (475 3075);
FORCEPROP 2 LAST SEC_TYPE 0402
J 0
(475 3075);
DISPLAY 1.021277 (475 3075);
PAINT ORANGE (475 3075);
DISPLAY INVISIBLE (475 3075);
FORCEADD OFFPAGE..1
(-550 4500);
FORCEPROP 2 LAST $XR0 104 
J 0
(-802 4500);
DISPLAY 0.638298 (-802 4500);
PAINT MONO (-802 4500);
FORCEPROP 2 LAST CDS_LIB mstr_standard
J 0
(-550 4500);
PAINT ORANGE (-550 4500);
DISPLAY INVISIBLE (-550 4500);
FORCEPROP 1 LAST OFFPAGE TRUE
J 0
(-225 4375);
DISPLAY 0.872340 (-225 4375);
PAINT GREEN (-225 4375);
DISPLAY INVISIBLE (-225 4375);
FORCEPROP 1 LAST COMMENT_BODY TRUE
J 0
(-425 4400);
DISPLAY 0.872340 (-425 4400);
PAINT GREEN (-425 4400);
DISPLAY INVISIBLE (-425 4400);
FORCEPROP 2 LAST PATH I54
J 0
(-500 4575);
DISPLAY 1.021277 (-500 4575);
PAINT ORANGE (-500 4575);
DISPLAY INVISIBLE (-500 4575);
FORCEADD OFFPAGE..1
(-550 3775);
FORCEPROP 2 LAST $XR0 104 
J 0
(-802 3775);
DISPLAY 0.638298 (-802 3775);
PAINT MONO (-802 3775);
FORCEPROP 2 LAST CDS_LIB mstr_standard
J 0
(-550 3775);
PAINT ORANGE (-550 3775);
DISPLAY INVISIBLE (-550 3775);
FORCEPROP 2 LAST PATH I55
J 0
(-500 3850);
DISPLAY 1.021277 (-500 3850);
PAINT ORANGE (-500 3850);
DISPLAY INVISIBLE (-500 3850);
FORCEPROP 1 LAST COMMENT_BODY TRUE
J 0
(-425 3675);
DISPLAY 0.872340 (-425 3675);
PAINT GREEN (-425 3675);
DISPLAY INVISIBLE (-425 3675);
FORCEPROP 1 LAST OFFPAGE TRUE
J 0
(-225 3650);
DISPLAY 0.872340 (-225 3650);
PAINT GREEN (-225 3650);
DISPLAY INVISIBLE (-225 3650);
FORCEADD OFFPAGE..1
(-550 3075);
FORCEPROP 2 LAST $XR0 104 
J 0
(-802 3075);
DISPLAY 0.638298 (-802 3075);
PAINT MONO (-802 3075);
FORCEPROP 1 LAST COMMENT_BODY TRUE
J 0
(-425 2975);
DISPLAY 0.872340 (-425 2975);
PAINT GREEN (-425 2975);
DISPLAY INVISIBLE (-425 2975);
FORCEPROP 1 LAST OFFPAGE TRUE
J 0
(-225 2950);
DISPLAY 0.872340 (-225 2950);
PAINT GREEN (-225 2950);
DISPLAY INVISIBLE (-225 2950);
FORCEPROP 2 LAST CDS_LIB mstr_standard
J 0
(-550 3075);
PAINT ORANGE (-550 3075);
DISPLAY INVISIBLE (-550 3075);
FORCEPROP 2 LAST PATH I56
J 0
(-500 3150);
DISPLAY 1.021277 (-500 3150);
PAINT ORANGE (-500 3150);
DISPLAY INVISIBLE (-500 3150);
FORCEADD OFFPAGE..2
(-2150 4875);
FORCEPROP 2 LAST $XR0 104 
J 0
(-1961 4875);
DISPLAY 0.638298 (-1961 4875);
PAINT MONO (-1961 4875);
FORCEPROP 1 LAST COMMENT_BODY TRUE
J 0
(-2195 4780);
DISPLAY 0.872340 (-2195 4780);
PAINT GREEN (-2195 4780);
DISPLAY INVISIBLE (-2195 4780);
FORCEPROP 2 LAST CDS_LIB mstr_standard
J 0
(-2150 4875);
PAINT ORANGE (-2150 4875);
DISPLAY INVISIBLE (-2150 4875);
FORCEPROP 1 LAST OFFPAGE TRUE
J 0
(-1825 4750);
DISPLAY 0.872340 (-1825 4750);
PAINT GREEN (-1825 4750);
DISPLAY INVISIBLE (-1825 4750);
FORCEPROP 2 LAST PATH I57
J 0
(-1975 4950);
DISPLAY 1.021277 (-1975 4950);
PAINT ORANGE (-1975 4950);
DISPLAY INVISIBLE (-1975 4950);
FORCEADD OFFPAGE..2
(-2150 4775);
FORCEPROP 2 LAST $XR0 104 
J 0
(-1961 4775);
DISPLAY 0.638298 (-1961 4775);
PAINT MONO (-1961 4775);
FORCEPROP 2 LAST CDS_LIB mstr_standard
J 0
(-2150 4775);
PAINT ORANGE (-2150 4775);
DISPLAY INVISIBLE (-2150 4775);
FORCEPROP 1 LAST COMMENT_BODY TRUE
J 0
(-2195 4680);
DISPLAY 0.872340 (-2195 4680);
PAINT GREEN (-2195 4680);
DISPLAY INVISIBLE (-2195 4680);
FORCEPROP 1 LAST OFFPAGE TRUE
J 0
(-1825 4650);
DISPLAY 0.872340 (-1825 4650);
PAINT GREEN (-1825 4650);
DISPLAY INVISIBLE (-1825 4650);
FORCEPROP 2 LAST PATH I58
J 0
(-1975 4850);
DISPLAY 1.021277 (-1975 4850);
PAINT ORANGE (-1975 4850);
DISPLAY INVISIBLE (-1975 4850);
FORCEADD OFFPAGE..2
(-2450 4025);
FORCEPROP 2 LAST $XR0 104 
J 0
(-2261 4025);
DISPLAY 0.638298 (-2261 4025);
PAINT MONO (-2261 4025);
FORCEPROP 1 LAST COMMENT_BODY TRUE
J 0
(-2495 3930);
DISPLAY 0.872340 (-2495 3930);
PAINT GREEN (-2495 3930);
DISPLAY INVISIBLE (-2495 3930);
FORCEPROP 2 LAST CDS_LIB mstr_standard
J 0
(-2450 4025);
PAINT ORANGE (-2450 4025);
DISPLAY INVISIBLE (-2450 4025);
FORCEPROP 1 LAST OFFPAGE TRUE
J 0
(-2125 3900);
DISPLAY 0.872340 (-2125 3900);
PAINT GREEN (-2125 3900);
DISPLAY INVISIBLE (-2125 3900);
FORCEPROP 2 LAST PATH I59
J 0
(-2275 4100);
DISPLAY 1.021277 (-2275 4100);
PAINT ORANGE (-2275 4100);
DISPLAY INVISIBLE (-2275 4100);
FORCEADD OFFPAGE..2
(-2450 3925);
FORCEPROP 2 LAST $XR0 104 
J 0
(-2261 3925);
DISPLAY 0.638298 (-2261 3925);
PAINT MONO (-2261 3925);
FORCEPROP 1 LAST COMMENT_BODY TRUE
J 0
(-2495 3830);
DISPLAY 0.872340 (-2495 3830);
PAINT GREEN (-2495 3830);
DISPLAY INVISIBLE (-2495 3830);
FORCEPROP 2 LAST CDS_LIB mstr_standard
J 0
(-2450 3925);
PAINT ORANGE (-2450 3925);
DISPLAY INVISIBLE (-2450 3925);
FORCEPROP 1 LAST OFFPAGE TRUE
J 0
(-2125 3800);
DISPLAY 0.872340 (-2125 3800);
PAINT GREEN (-2125 3800);
DISPLAY INVISIBLE (-2125 3800);
FORCEPROP 2 LAST PATH I60
J 0
(-2275 4000);
DISPLAY 1.021277 (-2275 4000);
PAINT ORANGE (-2275 4000);
DISPLAY INVISIBLE (-2275 4000);
FORCEADD RES..1
(525 5150);
FORCEPROP 1 LAST MATERIAL CHIP
J 1
(650 5100);
DISPLAY 0.617021 (650 5100);
PAINT SKYBLUE (650 5100);
FORCEPROP 1 LAST TOLERANCE 5%
J 0
(500 5100);
DISPLAY 0.617021 (500 5100);
PAINT SKYBLUE (500 5100);
FORCEPROP 1 LAST WATTAGE 1/16W
J 0
(350 5100);
DISPLAY 0.617021 (350 5100);
PAINT SKYBLUE (350 5100);
FORCEPROP 1 LAST PACK_TYPE 0402
J 0
(725 5100);
DISPLAY 0.617021 (725 5100);
PAINT SKYBLUE (725 5100);
FORCEPROP 1 LAST VALUE 0.0
J 1
(300 5100);
DISPLAY 0.617021 (300 5100);
PAINT SKYBLUE (300 5100);
FORCEPROP 1 LASTPIN (425 5150) $PN 1
J 0
(437 5162);
DISPLAY 0.617021 (437 5162);
PAINT ORANGE (437 5162);
FORCEPROP 1 LAST LOCATION R6F7
J 0
(475 5200);
DISPLAY 0.617021 (475 5200);
PAINT AQUA (475 5200);
FORCEPROP 1 LASTPIN (625 5150) $PN 2
J 0
(587 5162);
DISPLAY 0.617021 (587 5162);
PAINT ORANGE (587 5162);
FORCEPROP 1 LAST PART_NUMBER G21497-005
J 0
(650 5150);
DISPLAY 0.617021 (650 5150);
PAINT BLUE (650 5150);
FORCEPROP 1 LAST PATH I67
J 0
(475 5300);
DISPLAY 0.978723 (475 5300);
PAINT WHITE (475 5300);
DISPLAY INVISIBLE (475 5300);
FORCEPROP 0 LAST NO_XNET_CONNECTION 1
J 0
(475 5350);
PAINT MONO (475 5350);
DISPLAY INVISIBLE (475 5350);
FORCEPROP 0 LAST ROOM CLOCK_CPU0_OSC
J 0
(475 5300);
DISPLAY 1.021277 (475 5300);
PAINT ORANGE (475 5300);
DISPLAY INVISIBLE (475 5300);
FORCEPROP 2 LAST CDS_LOCATION R6F7
J 0
(475 5200);
DISPLAY 0.617021 (475 5200);
PAINT AQUA (475 5200);
DISPLAY INVISIBLE (475 5200);
FORCEPROP 2 LAST SEC 1
J 0
(475 5350);
DISPLAY 0.680851 (475 5350);
PAINT MONO (475 5350);
DISPLAY INVISIBLE (475 5350);
FORCEPROP 2 LAST SEC_TYPE 0402
J 0
(475 5350);
DISPLAY 1.021277 (475 5350);
PAINT ORANGE (475 5350);
DISPLAY INVISIBLE (475 5350);
FORCEPROP 2 LAST CDS_LIB mstr_discrete
J 0
(525 5150);
PAINT ORANGE (525 5150);
DISPLAY INVISIBLE (525 5150);
FORCEADD RES..1
(525 4500);
FORCEPROP 1 LAST VALUE 0.0
J 1
(300 4450);
DISPLAY 0.617021 (300 4450);
PAINT SKYBLUE (300 4450);
FORCEPROP 1 LAST WATTAGE 1/16W
J 0
(350 4450);
DISPLAY 0.617021 (350 4450);
PAINT SKYBLUE (350 4450);
FORCEPROP 1 LASTPIN (425 4500) $PN 1
J 0
(437 4512);
DISPLAY 0.617021 (437 4512);
PAINT ORANGE (437 4512);
FORCEPROP 1 LAST TOLERANCE 5%
J 0
(500 4450);
DISPLAY 0.617021 (500 4450);
PAINT SKYBLUE (500 4450);
FORCEPROP 1 LAST LOCATION R6F9
J 0
(475 4550);
DISPLAY 0.617021 (475 4550);
PAINT AQUA (475 4550);
FORCEPROP 1 LASTPIN (625 4500) $PN 2
J 0
(587 4512);
DISPLAY 0.617021 (587 4512);
PAINT ORANGE (587 4512);
FORCEPROP 1 LAST MATERIAL CHIP
J 1
(650 4450);
DISPLAY 0.617021 (650 4450);
PAINT SKYBLUE (650 4450);
FORCEPROP 1 LAST PACK_TYPE 0402
J 0
(725 4450);
DISPLAY 0.617021 (725 4450);
PAINT SKYBLUE (725 4450);
FORCEPROP 1 LAST PART_NUMBER G21497-005
J 0
(650 4500);
DISPLAY 0.617021 (650 4500);
PAINT BLUE (650 4500);
FORCEPROP 2 LAST CDS_LOCATION R6F9
J 0
(475 4550);
DISPLAY 0.617021 (475 4550);
PAINT AQUA (475 4550);
DISPLAY INVISIBLE (475 4550);
FORCEPROP 0 LAST ROOM CLOCK_CPU0_OSC
J 0
(475 4650);
DISPLAY 1.021277 (475 4650);
PAINT ORANGE (475 4650);
DISPLAY INVISIBLE (475 4650);
FORCEPROP 1 LAST PATH I68
J 0
(475 4650);
DISPLAY 0.978723 (475 4650);
PAINT WHITE (475 4650);
DISPLAY INVISIBLE (475 4650);
FORCEPROP 2 LAST SEC 1
J 0
(475 4700);
DISPLAY 0.680851 (475 4700);
PAINT MONO (475 4700);
DISPLAY INVISIBLE (475 4700);
FORCEPROP 0 LAST NO_XNET_CONNECTION 1
J 0
(475 4700);
PAINT MONO (475 4700);
DISPLAY INVISIBLE (475 4700);
FORCEPROP 2 LAST SEC_TYPE 0402
J 0
(475 4700);
DISPLAY 1.021277 (475 4700);
PAINT ORANGE (475 4700);
DISPLAY INVISIBLE (475 4700);
FORCEPROP 2 LAST CDS_LIB mstr_discrete
J 0
(525 4500);
PAINT ORANGE (525 4500);
DISPLAY INVISIBLE (525 4500);
FORCEADD RES..1
(525 3775);
FORCEPROP 1 LAST VALUE 0.0
J 1
(300 3725);
DISPLAY 0.617021 (300 3725);
PAINT SKYBLUE (300 3725);
FORCEPROP 1 LAST WATTAGE 1/16W
J 0
(350 3725);
DISPLAY 0.617021 (350 3725);
PAINT SKYBLUE (350 3725);
FORCEPROP 1 LASTPIN (425 3775) $PN 1
J 0
(437 3787);
DISPLAY 0.617021 (437 3787);
PAINT ORANGE (437 3787);
FORCEPROP 1 LAST TOLERANCE 5%
J 0
(500 3725);
DISPLAY 0.617021 (500 3725);
PAINT SKYBLUE (500 3725);
FORCEPROP 1 LAST LOCATION R3F2
J 0
(475 3825);
DISPLAY 0.617021 (475 3825);
PAINT AQUA (475 3825);
FORCEPROP 1 LASTPIN (625 3775) $PN 2
J 0
(587 3787);
DISPLAY 0.617021 (587 3787);
PAINT ORANGE (587 3787);
FORCEPROP 1 LAST MATERIAL CHIP
J 1
(650 3725);
DISPLAY 0.617021 (650 3725);
PAINT SKYBLUE (650 3725);
FORCEPROP 1 LAST PACK_TYPE 0402
J 1
(775 3725);
DISPLAY 0.617021 (775 3725);
PAINT SKYBLUE (775 3725);
FORCEPROP 1 LAST PART_NUMBER G21497-005
J 0
(650 3775);
DISPLAY 0.617021 (650 3775);
PAINT BLUE (650 3775);
FORCEPROP 2 LAST CDS_LOCATION R3F2
J 0
(475 3825);
DISPLAY 0.617021 (475 3825);
PAINT AQUA (475 3825);
DISPLAY INVISIBLE (475 3825);
FORCEPROP 0 LAST NO_XNET_CONNECTION 1
J 0
(475 3975);
PAINT MONO (475 3975);
DISPLAY INVISIBLE (475 3975);
FORCEPROP 0 LAST ROOM CLOCK_CPU1_OSC
J 0
(475 3925);
DISPLAY 1.021277 (475 3925);
PAINT ORANGE (475 3925);
DISPLAY INVISIBLE (475 3925);
FORCEPROP 1 LAST PATH I69
J 0
(475 3925);
DISPLAY 0.978723 (475 3925);
PAINT WHITE (475 3925);
DISPLAY INVISIBLE (475 3925);
FORCEPROP 2 LAST SEC 1
J 0
(475 3975);
DISPLAY 0.680851 (475 3975);
PAINT MONO (475 3975);
DISPLAY INVISIBLE (475 3975);
FORCEPROP 2 LAST SEC_TYPE 0402
J 0
(475 3975);
DISPLAY 1.021277 (475 3975);
PAINT ORANGE (475 3975);
DISPLAY INVISIBLE (475 3975);
FORCEPROP 2 LAST CDS_LIB mstr_discrete
J 0
(525 3775);
PAINT ORANGE (525 3775);
DISPLAY INVISIBLE (525 3775);
FORCEADD RES..1
(525 3075);
FORCEPROP 1 LAST VALUE 0.0
J 1
(300 3025);
DISPLAY 0.617021 (300 3025);
PAINT SKYBLUE (300 3025);
FORCEPROP 1 LAST WATTAGE 1/16W
J 0
(350 3025);
DISPLAY 0.617021 (350 3025);
PAINT SKYBLUE (350 3025);
FORCEPROP 1 LAST TOLERANCE 5%
J 0
(500 3025);
DISPLAY 0.617021 (500 3025);
PAINT SKYBLUE (500 3025);
FORCEPROP 1 LAST MATERIAL CHIP
J 1
(650 3025);
DISPLAY 0.617021 (650 3025);
PAINT SKYBLUE (650 3025);
FORCEPROP 1 LAST PACK_TYPE 0402
J 1
(775 3025);
DISPLAY 0.617021 (775 3025);
PAINT SKYBLUE (775 3025);
FORCEPROP 1 LASTPIN (425 3075) $PN 1
J 0
(437 3087);
DISPLAY 0.617021 (437 3087);
PAINT ORANGE (437 3087);
FORCEPROP 1 LAST LOCATION R3F4
J 0
(475 3125);
DISPLAY 0.617021 (475 3125);
PAINT AQUA (475 3125);
FORCEPROP 1 LASTPIN (625 3075) $PN 2
J 0
(587 3087);
DISPLAY 0.617021 (587 3087);
PAINT ORANGE (587 3087);
FORCEPROP 1 LAST PART_NUMBER G21497-005
J 0
(650 3075);
DISPLAY 0.617021 (650 3075);
PAINT BLUE (650 3075);
FORCEPROP 2 LAST CDS_LOCATION R3F4
J 0
(475 3125);
DISPLAY 0.617021 (475 3125);
PAINT AQUA (475 3125);
DISPLAY INVISIBLE (475 3125);
FORCEPROP 0 LAST NO_XNET_CONNECTION 1
J 0
(475 3275);
PAINT MONO (475 3275);
DISPLAY INVISIBLE (475 3275);
FORCEPROP 0 LAST ROOM CLOCK_CPU1_OSC
J 0
(475 3225);
DISPLAY 1.021277 (475 3225);
PAINT ORANGE (475 3225);
DISPLAY INVISIBLE (475 3225);
FORCEPROP 1 LAST PATH I70
J 0
(475 3225);
DISPLAY 0.978723 (475 3225);
PAINT WHITE (475 3225);
DISPLAY INVISIBLE (475 3225);
FORCEPROP 2 LAST SEC 1
J 0
(475 3275);
DISPLAY 0.680851 (475 3275);
PAINT MONO (475 3275);
DISPLAY INVISIBLE (475 3275);
FORCEPROP 2 LAST SEC_TYPE 0402
J 0
(475 3275);
DISPLAY 1.021277 (475 3275);
PAINT ORANGE (475 3275);
DISPLAY INVISIBLE (475 3275);
FORCEPROP 2 LAST CDS_LIB mstr_discrete
J 0
(525 3075);
PAINT ORANGE (525 3075);
DISPLAY INVISIBLE (525 3075);
FORCEADD OSC_C..17
(-3400 4775);
FORCEPROP 2 LASTPIN (-3900 4675) $PN 2
J 2
(-3910 4685);
DISPLAY 0.617021 (-3910 4685);
PAINT ORANGE (-3910 4685);
FORCEPROP 2 LASTPIN (-3900 4775) $PN 1
J 2
(-3910 4785);
DISPLAY 0.617021 (-3910 4785);
PAINT ORANGE (-3910 4785);
FORCEPROP 2 LASTPIN (-3900 4875) $PN 6
J 2
(-3910 4885);
DISPLAY 0.617021 (-3910 4885);
PAINT ORANGE (-3910 4885);
FORCEPROP 1 LAST VALUE 156.25MHZ
J 0
(-3850 5000);
DISPLAY 0.617021 (-3850 5000);
PAINT SKYBLUE (-3850 5000);
FORCEPROP 1 LAST MATERIAL OSC
J 0
(-3850 5050);
DISPLAY 0.617021 (-3850 5050);
PAINT SKYBLUE (-3850 5050);
FORCEPROP 1 LAST PART_NUMBER G63831-004
J 0
(-3850 4525);
DISPLAY 0.617021 (-3850 4525);
PAINT BLUE (-3850 4525);
FORCEPROP 1 LAST LOCATION Y6F1
J 0
(-3850 5100);
DISPLAY 0.617021 (-3850 5100);
PAINT AQUA (-3850 5100);
FORCEPROP 2 LASTPIN (-2900 4875) $PN 5
J 0
(-2890 4885);
DISPLAY 0.617021 (-2890 4885);
PAINT ORANGE (-2890 4885);
FORCEPROP 2 LASTPIN (-2900 4675) $PN 3
J 0
(-2890 4685);
DISPLAY 0.617021 (-2890 4685);
PAINT ORANGE (-2890 4685);
FORCEPROP 2 LASTPIN (-2900 4775) $PN 4
J 0
(-2890 4785);
DISPLAY 0.617021 (-2890 4785);
PAINT ORANGE (-2890 4785);
FORCEPROP 1 LAST CDS_LMAN_SYM_OUTLINE -450,200,450,-200
J 0
(-3400 4775);
DISPLAY 0.468085 (-3400 4775);
PAINT GREEN (-3400 4775);
DISPLAY INVISIBLE (-3400 4775);
FORCEPROP 2 LAST CDS_LIB mstr_discrete
J 0
(-3400 4775);
PAINT ORANGE (-3400 4775);
DISPLAY INVISIBLE (-3400 4775);
FORCEPROP 1 LAST PATH I71
J 0
(-3355 5005);
PAINT GREEN (-3355 5005);
DISPLAY INVISIBLE (-3355 5005);
FORCEPROP 2 LAST CDS_LOCATION Y6F1
J 0
(-3850 5100);
DISPLAY 0.617021 (-3850 5100);
PAINT AQUA (-3850 5100);
DISPLAY INVISIBLE (-3850 5100);
FORCEPROP 2 LAST SEC_TYPE 6P10
J 0
(-3850 5150);
DISPLAY 1.021277 (-3850 5150);
PAINT ORANGE (-3850 5150);
DISPLAY INVISIBLE (-3850 5150);
FORCEPROP 2 LAST SEC 1
J 0
(-3850 5150);
DISPLAY 0.680851 (-3850 5150);
PAINT MONO (-3850 5150);
DISPLAY INVISIBLE (-3850 5150);
FORCEPROP 1 LAST PACK_TYPE 6P10
J 0
(-3850 5150);
PAINT SKYBLUE (-3850 5150);
DISPLAY INVISIBLE (-3850 5150);
FORCEADD OSC_C..17
(-3700 3925);
FORCEPROP 2 LASTPIN (-4200 3825) $PN 2
J 2
(-4210 3835);
DISPLAY 0.617021 (-4210 3835);
PAINT ORANGE (-4210 3835);
FORCEPROP 2 LASTPIN (-4200 4025) $PN 6
J 2
(-4210 4035);
DISPLAY 0.617021 (-4210 4035);
PAINT ORANGE (-4210 4035);
FORCEPROP 2 LASTPIN (-4200 3925) $PN 1
J 2
(-4210 3935);
DISPLAY 0.617021 (-4210 3935);
PAINT ORANGE (-4210 3935);
FORCEPROP 1 LAST MATERIAL OSC
J 0
(-4150 4200);
DISPLAY 0.617021 (-4150 4200);
PAINT SKYBLUE (-4150 4200);
FORCEPROP 1 LAST VALUE 156.25MHZ
J 0
(-4150 4150);
DISPLAY 0.617021 (-4150 4150);
PAINT SKYBLUE (-4150 4150);
FORCEPROP 1 LAST PART_NUMBER G63831-004
J 0
(-4150 3675);
DISPLAY 0.617021 (-4150 3675);
PAINT BLUE (-4150 3675);
FORCEPROP 1 LAST LOCATION Y3F1
J 0
(-4150 4250);
DISPLAY 0.617021 (-4150 4250);
PAINT AQUA (-4150 4250);
FORCEPROP 2 LASTPIN (-3200 3825) $PN 3
J 0
(-3190 3835);
DISPLAY 0.617021 (-3190 3835);
PAINT ORANGE (-3190 3835);
FORCEPROP 2 LASTPIN (-3200 4025) $PN 5
J 0
(-3190 4035);
DISPLAY 0.617021 (-3190 4035);
PAINT ORANGE (-3190 4035);
FORCEPROP 2 LASTPIN (-3200 3925) $PN 4
J 0
(-3190 3935);
DISPLAY 0.617021 (-3190 3935);
PAINT ORANGE (-3190 3935);
FORCEPROP 2 LAST SEC 1
J 0
(-4150 4300);
DISPLAY 0.680851 (-4150 4300);
PAINT MONO (-4150 4300);
DISPLAY INVISIBLE (-4150 4300);
FORCEPROP 2 LAST CDS_LOCATION Y3F1
J 0
(-4150 4250);
DISPLAY 0.617021 (-4150 4250);
PAINT AQUA (-4150 4250);
DISPLAY INVISIBLE (-4150 4250);
FORCEPROP 2 LAST SEC_TYPE 6P10
J 0
(-4150 4300);
DISPLAY 1.021277 (-4150 4300);
PAINT ORANGE (-4150 4300);
DISPLAY INVISIBLE (-4150 4300);
FORCEPROP 1 LAST PACK_TYPE 6P10
J 0
(-4150 4300);
PAINT SKYBLUE (-4150 4300);
DISPLAY INVISIBLE (-4150 4300);
FORCEPROP 2 LAST CDS_LIB mstr_discrete
J 0
(-3700 3925);
PAINT ORANGE (-3700 3925);
DISPLAY INVISIBLE (-3700 3925);
FORCEPROP 1 LAST CDS_LMAN_SYM_OUTLINE -450,200,450,-200
J 0
(-3700 3925);
DISPLAY 0.468085 (-3700 3925);
PAINT GREEN (-3700 3925);
DISPLAY INVISIBLE (-3700 3925);
FORCEPROP 1 LAST PATH I72
J 0
(-3655 4155);
PAINT GREEN (-3655 4155);
DISPLAY INVISIBLE (-3655 4155);
FORCEADD OFFPAGE..1
(-550 4950);
FORCEPROP 2 LAST $XR0 194 
J 0
(-802 4950);
DISPLAY 0.638298 (-802 4950);
PAINT MONO (-802 4950);
FORCEPROP 2 LAST CDS_LIB mstr_standard
J 0
(-550 4950);
PAINT ORANGE (-550 4950);
DISPLAY INVISIBLE (-550 4950);
FORCEPROP 1 LAST OFFPAGE TRUE
J 0
(-225 4825);
DISPLAY 0.872340 (-225 4825);
PAINT GREEN (-225 4825);
DISPLAY INVISIBLE (-225 4825);
FORCEPROP 1 LAST COMMENT_BODY TRUE
J 0
(-425 4850);
DISPLAY 0.872340 (-425 4850);
PAINT GREEN (-425 4850);
DISPLAY INVISIBLE (-425 4850);
FORCEPROP 2 LAST PATH I74
J 0
(-500 5025);
DISPLAY 1.021277 (-500 5025);
PAINT ORANGE (-500 5025);
DISPLAY INVISIBLE (-500 5025);
FORCEADD OFFPAGE..1
(-550 4300);
FORCEPROP 2 LAST $XR0 194 
J 0
(-802 4300);
DISPLAY 0.638298 (-802 4300);
PAINT MONO (-802 4300);
FORCEPROP 2 LAST CDS_LIB mstr_standard
J 0
(-550 4300);
PAINT ORANGE (-550 4300);
DISPLAY INVISIBLE (-550 4300);
FORCEPROP 1 LAST OFFPAGE TRUE
J 0
(-225 4175);
DISPLAY 0.872340 (-225 4175);
PAINT GREEN (-225 4175);
DISPLAY INVISIBLE (-225 4175);
FORCEPROP 1 LAST COMMENT_BODY TRUE
J 0
(-425 4200);
DISPLAY 0.872340 (-425 4200);
PAINT GREEN (-425 4200);
DISPLAY INVISIBLE (-425 4200);
FORCEPROP 2 LAST PATH I76
J 0
(-500 4375);
DISPLAY 1.021277 (-500 4375);
PAINT ORANGE (-500 4375);
DISPLAY INVISIBLE (-500 4375);
FORCEADD OFFPAGE..2
(1675 4750);
FORCEPROP 2 LAST $XR0 22 
J 0
(1864 4750);
DISPLAY 0.638298 (1864 4750);
PAINT MONO (1864 4750);
FORCEPROP 1 LAST COMMENT_BODY TRUE
J 0
(1630 4655);
DISPLAY 0.872340 (1630 4655);
PAINT GREEN (1630 4655);
DISPLAY INVISIBLE (1630 4655);
FORCEPROP 2 LAST CDS_LIB mstr_standard
J 0
(1675 4750);
PAINT ORANGE (1675 4750);
DISPLAY INVISIBLE (1675 4750);
FORCEPROP 2 LAST PATH I77
J 0
(1850 4825);
DISPLAY 1.021277 (1850 4825);
PAINT ORANGE (1850 4825);
DISPLAY INVISIBLE (1850 4825);
FORCEPROP 1 LAST OFFPAGE TRUE
J 0
(2000 4625);
DISPLAY 0.872340 (2000 4625);
PAINT GREEN (2000 4625);
DISPLAY INVISIBLE (2000 4625);
FORCEADD RES..1
(525 4750);
FORCEPROP 1 LAST VALUE 0.0
J 1
(300 4700);
DISPLAY 0.617021 (300 4700);
PAINT SKYBLUE (300 4700);
FORCEPROP 1 LAST WATTAGE 1/16W
J 0
(350 4700);
DISPLAY 0.617021 (350 4700);
PAINT SKYBLUE (350 4700);
FORCEPROP 1 LASTPIN (425 4750) $PN 1
J 0
(437 4762);
DISPLAY 0.617021 (437 4762);
PAINT ORANGE (437 4762);
FORCEPROP 1 LAST TOLERANCE 5%
J 0
(500 4700);
DISPLAY 0.617021 (500 4700);
PAINT SKYBLUE (500 4700);
FORCEPROP 1 LAST LOCATION R6F10
J 0
(475 4800);
DISPLAY 0.617021 (475 4800);
PAINT AQUA (475 4800);
FORCEPROP 1 LASTPIN (625 4750) $PN 2
J 0
(587 4762);
DISPLAY 0.617021 (587 4762);
PAINT ORANGE (587 4762);
FORCEPROP 1 LAST MATERIAL EMPTY
J 1
(650 4700);
DISPLAY 0.617021 (650 4700);
PAINT RED (650 4700);
FORCEPROP 1 LAST PACK_TYPE 0402
J 0
(725 4700);
DISPLAY 0.617021 (725 4700);
PAINT SKYBLUE (725 4700);
FORCEPROP 1 LAST PART_NUMBER G21497-005
J 0
(675 4750);
DISPLAY 0.617021 (675 4750);
PAINT BLUE (675 4750);
FORCEPROP 1 LAST PATH I78
J 0
(475 4900);
DISPLAY 0.978723 (475 4900);
PAINT WHITE (475 4900);
DISPLAY INVISIBLE (475 4900);
FORCEPROP 2 LAST SEC 1
J 0
(475 4950);
DISPLAY 0.680851 (475 4950);
PAINT MONO (475 4950);
DISPLAY INVISIBLE (475 4950);
FORCEPROP 2 LAST SEC_TYPE 0402
J 0
(475 4950);
DISPLAY 1.021277 (475 4950);
PAINT ORANGE (475 4950);
DISPLAY INVISIBLE (475 4950);
FORCEPROP 2 LAST CDS_LIB mstr_discrete
J 0
(525 4750);
PAINT ORANGE (525 4750);
DISPLAY INVISIBLE (525 4750);
FORCEADD RES..1
(525 4100);
FORCEPROP 1 LAST WATTAGE 1/16W
J 0
(350 4050);
DISPLAY 0.617021 (350 4050);
PAINT SKYBLUE (350 4050);
FORCEPROP 1 LAST VALUE 0.0
J 1
(300 4050);
DISPLAY 0.617021 (300 4050);
PAINT SKYBLUE (300 4050);
FORCEPROP 1 LAST TOLERANCE 5%
J 0
(500 4050);
DISPLAY 0.617021 (500 4050);
PAINT SKYBLUE (500 4050);
FORCEPROP 1 LAST MATERIAL EMPTY
J 1
(650 4050);
DISPLAY 0.617021 (650 4050);
PAINT RED (650 4050);
FORCEPROP 1 LAST PACK_TYPE 0402
J 0
(725 4050);
DISPLAY 0.617021 (725 4050);
PAINT SKYBLUE (725 4050);
FORCEPROP 1 LASTPIN (425 4100) $PN 1
J 0
(437 4112);
DISPLAY 0.617021 (437 4112);
PAINT ORANGE (437 4112);
FORCEPROP 1 LAST LOCATION R6F11
J 0
(475 4150);
DISPLAY 0.617021 (475 4150);
PAINT AQUA (475 4150);
FORCEPROP 1 LASTPIN (625 4100) $PN 2
J 0
(587 4112);
DISPLAY 0.617021 (587 4112);
PAINT ORANGE (587 4112);
FORCEPROP 1 LAST PART_NUMBER G21497-005
J 0
(650 4100);
DISPLAY 0.617021 (650 4100);
PAINT BLUE (650 4100);
FORCEPROP 1 LAST PATH I79
J 0
(475 4250);
DISPLAY 0.978723 (475 4250);
PAINT WHITE (475 4250);
DISPLAY INVISIBLE (475 4250);
FORCEPROP 2 LAST SEC 1
J 0
(475 4300);
DISPLAY 0.680851 (475 4300);
PAINT MONO (475 4300);
DISPLAY INVISIBLE (475 4300);
FORCEPROP 2 LAST SEC_TYPE 0402
J 0
(475 4300);
DISPLAY 1.021277 (475 4300);
PAINT ORANGE (475 4300);
DISPLAY INVISIBLE (475 4300);
FORCEPROP 2 LAST CDS_LIB mstr_discrete
J 0
(525 4100);
PAINT ORANGE (525 4100);
DISPLAY INVISIBLE (525 4100);
FORCEADD OFFPAGE..2
(1675 4100);
FORCEPROP 2 LAST $XR0 22 
J 0
(1864 4100);
DISPLAY 0.638298 (1864 4100);
PAINT MONO (1864 4100);
FORCEPROP 1 LAST COMMENT_BODY TRUE
J 0
(1630 4005);
DISPLAY 0.872340 (1630 4005);
PAINT GREEN (1630 4005);
DISPLAY INVISIBLE (1630 4005);
FORCEPROP 1 LAST OFFPAGE TRUE
J 0
(2000 3975);
DISPLAY 0.872340 (2000 3975);
PAINT GREEN (2000 3975);
DISPLAY INVISIBLE (2000 3975);
FORCEPROP 2 LAST CDS_LIB mstr_standard
J 0
(1675 4100);
PAINT ORANGE (1675 4100);
DISPLAY INVISIBLE (1675 4100);
FORCEPROP 2 LAST PATH I80
J 0
(1850 4175);
DISPLAY 1.021277 (1850 4175);
PAINT ORANGE (1850 4175);
DISPLAY INVISIBLE (1850 4175);
FORCEADD OFFPAGE..1
(-550 3575);
FORCEPROP 2 LAST $XR0 193 
J 0
(-802 3575);
DISPLAY 0.638298 (-802 3575);
PAINT MONO (-802 3575);
FORCEPROP 2 LAST CDS_LIB mstr_standard
J 0
(-550 3575);
PAINT ORANGE (-550 3575);
DISPLAY INVISIBLE (-550 3575);
FORCEPROP 2 LAST PATH I81
J 0
(-500 3650);
DISPLAY 1.021277 (-500 3650);
PAINT ORANGE (-500 3650);
DISPLAY INVISIBLE (-500 3650);
FORCEPROP 1 LAST COMMENT_BODY TRUE
J 0
(-425 3475);
DISPLAY 0.872340 (-425 3475);
PAINT GREEN (-425 3475);
DISPLAY INVISIBLE (-425 3475);
FORCEPROP 1 LAST OFFPAGE TRUE
J 0
(-225 3450);
DISPLAY 0.872340 (-225 3450);
PAINT GREEN (-225 3450);
DISPLAY INVISIBLE (-225 3450);
FORCEADD OFFPAGE..2
(1675 3375);
FORCEPROP 2 LAST $XR0 56 
J 0
(1864 3375);
DISPLAY 0.638298 (1864 3375);
PAINT MONO (1864 3375);
FORCEPROP 1 LAST COMMENT_BODY TRUE
J 0
(1630 3280);
DISPLAY 0.872340 (1630 3280);
PAINT GREEN (1630 3280);
DISPLAY INVISIBLE (1630 3280);
FORCEPROP 2 LAST CDS_LIB mstr_standard
J 0
(1675 3375);
PAINT ORANGE (1675 3375);
DISPLAY INVISIBLE (1675 3375);
FORCEPROP 1 LAST OFFPAGE TRUE
J 0
(2000 3250);
DISPLAY 0.872340 (2000 3250);
PAINT GREEN (2000 3250);
DISPLAY INVISIBLE (2000 3250);
FORCEPROP 2 LAST PATH I83
J 0
(1850 3450);
DISPLAY 1.021277 (1850 3450);
PAINT ORANGE (1850 3450);
DISPLAY INVISIBLE (1850 3450);
FORCEADD RES..1
(525 3375);
FORCEPROP 1 LAST WATTAGE 1/16W
J 0
(350 3325);
DISPLAY 0.617021 (350 3325);
PAINT SKYBLUE (350 3325);
FORCEPROP 1 LAST VALUE 0.0
J 1
(300 3325);
DISPLAY 0.617021 (300 3325);
PAINT SKYBLUE (300 3325);
FORCEPROP 1 LASTPIN (425 3375) $PN 1
J 0
(437 3387);
DISPLAY 0.617021 (437 3387);
PAINT ORANGE (437 3387);
FORCEPROP 1 LAST LOCATION R3F5
J 0
(475 3425);
DISPLAY 0.617021 (475 3425);
PAINT AQUA (475 3425);
FORCEPROP 1 LAST TOLERANCE 5%
J 0
(500 3325);
DISPLAY 0.617021 (500 3325);
PAINT SKYBLUE (500 3325);
FORCEPROP 1 LAST MATERIAL EMPTY
J 1
(650 3325);
DISPLAY 0.617021 (650 3325);
PAINT RED (650 3325);
FORCEPROP 1 LASTPIN (625 3375) $PN 2
J 0
(587 3387);
DISPLAY 0.617021 (587 3387);
PAINT ORANGE (587 3387);
FORCEPROP 1 LAST PACK_TYPE 0402
J 1
(775 3325);
DISPLAY 0.617021 (775 3325);
PAINT SKYBLUE (775 3325);
FORCEPROP 1 LAST PART_NUMBER G21497-005
J 0
(650 3375);
DISPLAY 0.617021 (650 3375);
PAINT BLUE (650 3375);
FORCEPROP 1 LAST PATH I84
J 0
(475 3525);
DISPLAY 0.978723 (475 3525);
PAINT WHITE (475 3525);
DISPLAY INVISIBLE (475 3525);
FORCEPROP 2 LAST SEC 1
J 0
(475 3575);
DISPLAY 0.680851 (475 3575);
PAINT MONO (475 3575);
DISPLAY INVISIBLE (475 3575);
FORCEPROP 2 LAST SEC_TYPE 0402
J 0
(475 3575);
DISPLAY 1.021277 (475 3575);
PAINT ORANGE (475 3575);
DISPLAY INVISIBLE (475 3575);
FORCEPROP 2 LAST CDS_LIB mstr_discrete
J 0
(525 3375);
PAINT ORANGE (525 3375);
DISPLAY INVISIBLE (525 3375);
FORCEADD OFFPAGE..1
(-550 2875);
FORCEPROP 2 LAST $XR0 193 
J 0
(-802 2875);
DISPLAY 0.638298 (-802 2875);
PAINT MONO (-802 2875);
FORCEPROP 2 LAST CDS_LIB mstr_standard
J 0
(-550 2875);
PAINT ORANGE (-550 2875);
DISPLAY INVISIBLE (-550 2875);
FORCEPROP 2 LAST PATH I86
J 0
(-500 2950);
DISPLAY 1.021277 (-500 2950);
PAINT ORANGE (-500 2950);
DISPLAY INVISIBLE (-500 2950);
FORCEPROP 1 LAST COMMENT_BODY TRUE
J 0
(-425 2775);
DISPLAY 0.872340 (-425 2775);
PAINT GREEN (-425 2775);
DISPLAY INVISIBLE (-425 2775);
FORCEPROP 1 LAST OFFPAGE TRUE
J 0
(-225 2750);
DISPLAY 0.872340 (-225 2750);
PAINT GREEN (-225 2750);
DISPLAY INVISIBLE (-225 2750);
FORCEADD OFFPAGE..2
(1675 2675);
FORCEPROP 2 LAST $XR0 56 
J 0
(1864 2675);
DISPLAY 0.638298 (1864 2675);
PAINT MONO (1864 2675);
FORCEPROP 1 LAST OFFPAGE TRUE
J 0
(2000 2550);
DISPLAY 0.872340 (2000 2550);
PAINT GREEN (2000 2550);
DISPLAY INVISIBLE (2000 2550);
FORCEPROP 1 LAST COMMENT_BODY TRUE
J 0
(1630 2580);
DISPLAY 0.872340 (1630 2580);
PAINT GREEN (1630 2580);
DISPLAY INVISIBLE (1630 2580);
FORCEPROP 2 LAST CDS_LIB mstr_standard
J 0
(1675 2675);
PAINT ORANGE (1675 2675);
DISPLAY INVISIBLE (1675 2675);
FORCEPROP 2 LAST PATH I87
J 0
(1850 2750);
DISPLAY 1.021277 (1850 2750);
PAINT ORANGE (1850 2750);
DISPLAY INVISIBLE (1850 2750);
FORCEADD RES..1
(525 2675);
FORCEPROP 1 LAST VALUE 0.0
J 1
(300 2625);
DISPLAY 0.617021 (300 2625);
PAINT SKYBLUE (300 2625);
FORCEPROP 1 LAST WATTAGE 1/16W
J 0
(350 2625);
DISPLAY 0.617021 (350 2625);
PAINT SKYBLUE (350 2625);
FORCEPROP 1 LASTPIN (425 2675) $PN 1
J 0
(437 2687);
DISPLAY 0.617021 (437 2687);
PAINT ORANGE (437 2687);
FORCEPROP 1 LAST LOCATION R3F6
J 0
(475 2725);
DISPLAY 0.617021 (475 2725);
PAINT AQUA (475 2725);
FORCEPROP 1 LAST TOLERANCE 5%
J 0
(500 2625);
DISPLAY 0.617021 (500 2625);
PAINT SKYBLUE (500 2625);
FORCEPROP 1 LASTPIN (625 2675) $PN 2
J 0
(587 2687);
DISPLAY 0.617021 (587 2687);
PAINT ORANGE (587 2687);
FORCEPROP 1 LAST MATERIAL EMPTY
J 1
(650 2625);
DISPLAY 0.617021 (650 2625);
PAINT RED (650 2625);
FORCEPROP 1 LAST PART_NUMBER G21497-005
J 0
(650 2675);
DISPLAY 0.617021 (650 2675);
PAINT BLUE (650 2675);
FORCEPROP 1 LAST PACK_TYPE 0402
J 1
(775 2625);
DISPLAY 0.617021 (775 2625);
PAINT SKYBLUE (775 2625);
FORCEPROP 1 LAST PATH I88
J 0
(475 2825);
DISPLAY 0.978723 (475 2825);
PAINT WHITE (475 2825);
DISPLAY INVISIBLE (475 2825);
FORCEPROP 2 LAST SEC 1
J 0
(475 2875);
DISPLAY 0.680851 (475 2875);
PAINT MONO (475 2875);
DISPLAY INVISIBLE (475 2875);
FORCEPROP 2 LAST SEC_TYPE 0402
J 0
(475 2875);
DISPLAY 1.021277 (475 2875);
PAINT ORANGE (475 2875);
DISPLAY INVISIBLE (475 2875);
FORCEPROP 2 LAST CDS_LIB mstr_discrete
J 0
(525 2675);
PAINT ORANGE (525 2675);
DISPLAY INVISIBLE (525 2675);
FORCEADD OFFPAGE..2
(1700 1100);
FORCEPROP 2 LAST $XR0 193 
J 0
(1889 1100);
DISPLAY 0.638298 (1889 1100);
PAINT MONO (1889 1100);
FORCEPROP 1 LAST OFFPAGE TRUE
J 0
(2025 975);
DISPLAY 0.872340 (2025 975);
PAINT GREEN (2025 975);
DISPLAY INVISIBLE (2025 975);
FORCEPROP 1 LAST COMMENT_BODY TRUE
J 0
(1655 1005);
DISPLAY 0.872340 (1655 1005);
PAINT GREEN (1655 1005);
DISPLAY INVISIBLE (1655 1005);
FORCEPROP 2 LAST CDS_LIB mstr_standard
J 0
(1700 1100);
PAINT ORANGE (1700 1100);
DISPLAY INVISIBLE (1700 1100);
FORCEPROP 2 LAST PATH I89
J 0
(1875 1175);
DISPLAY 1.021277 (1875 1175);
PAINT ORANGE (1875 1175);
DISPLAY INVISIBLE (1875 1175);
FORCEADD OFFPAGE..2
(1700 2200);
FORCEPROP 2 LAST $XR0 104 
J 0
(1889 2200);
DISPLAY 0.638298 (1889 2200);
PAINT MONO (1889 2200);
FORCEPROP 1 LAST COMMENT_BODY TRUE
J 0
(1655 2105);
DISPLAY 0.872340 (1655 2105);
PAINT GREEN (1655 2105);
DISPLAY INVISIBLE (1655 2105);
FORCEPROP 2 LAST CDS_LIB mstr_standard
J 0
(1700 2200);
PAINT ORANGE (1700 2200);
DISPLAY INVISIBLE (1700 2200);
FORCEPROP 2 LAST PATH I90
J 0
(1875 2275);
DISPLAY 1.021277 (1875 2275);
PAINT ORANGE (1875 2275);
DISPLAY INVISIBLE (1875 2275);
FORCEPROP 1 LAST OFFPAGE TRUE
J 0
(2025 2075);
DISPLAY 0.872340 (2025 2075);
PAINT GREEN (2025 2075);
DISPLAY INVISIBLE (2025 2075);
FORCEADD OFFPAGE..2
(1700 1800);
FORCEPROP 2 LAST $XR0 194 
J 0
(1889 1800);
DISPLAY 0.638298 (1889 1800);
PAINT MONO (1889 1800);
FORCEPROP 1 LAST COMMENT_BODY TRUE
J 0
(1655 1705);
DISPLAY 0.872340 (1655 1705);
PAINT GREEN (1655 1705);
DISPLAY INVISIBLE (1655 1705);
FORCEPROP 2 LAST CDS_LIB mstr_standard
J 0
(1700 1800);
PAINT ORANGE (1700 1800);
DISPLAY INVISIBLE (1700 1800);
FORCEPROP 2 LAST PATH I91
J 0
(1875 1875);
DISPLAY 1.021277 (1875 1875);
PAINT ORANGE (1875 1875);
DISPLAY INVISIBLE (1875 1875);
FORCEPROP 1 LAST OFFPAGE TRUE
J 0
(2025 1675);
DISPLAY 0.872340 (2025 1675);
PAINT GREEN (2025 1675);
DISPLAY INVISIBLE (2025 1675);
FORCEADD OFFPAGE..2
(1700 1500);
FORCEPROP 2 LAST $XR0 104 
J 0
(1889 1500);
DISPLAY 0.638298 (1889 1500);
PAINT MONO (1889 1500);
FORCEPROP 1 LAST COMMENT_BODY TRUE
J 0
(1655 1405);
DISPLAY 0.872340 (1655 1405);
PAINT GREEN (1655 1405);
DISPLAY INVISIBLE (1655 1405);
FORCEPROP 1 LAST OFFPAGE TRUE
J 0
(2025 1375);
DISPLAY 0.872340 (2025 1375);
PAINT GREEN (2025 1375);
DISPLAY INVISIBLE (2025 1375);
FORCEPROP 2 LAST CDS_LIB mstr_standard
J 0
(1700 1500);
PAINT ORANGE (1700 1500);
DISPLAY INVISIBLE (1700 1500);
FORCEPROP 2 LAST PATH I92
J 0
(1875 1575);
DISPLAY 1.021277 (1875 1575);
PAINT ORANGE (1875 1575);
DISPLAY INVISIBLE (1875 1575);
FORCEADD RES..1
(550 2200);
FORCEPROP 1 LASTPIN (450 2200) $PN 1
J 0
(462 2212);
DISPLAY 0.617021 (462 2212);
PAINT ORANGE (462 2212);
FORCEPROP 1 LAST VALUE 0.0
J 1
(325 2150);
DISPLAY 0.617021 (325 2150);
PAINT SKYBLUE (325 2150);
FORCEPROP 1 LAST WATTAGE 1/16W
J 0
(375 2150);
DISPLAY 0.617021 (375 2150);
PAINT SKYBLUE (375 2150);
FORCEPROP 1 LAST LOCATION R8D43
J 0
(500 2250);
DISPLAY 0.617021 (500 2250);
PAINT AQUA (500 2250);
FORCEPROP 1 LAST TOLERANCE 5%
J 0
(525 2150);
DISPLAY 0.617021 (525 2150);
PAINT SKYBLUE (525 2150);
FORCEPROP 1 LASTPIN (650 2200) $PN 2
J 0
(612 2212);
DISPLAY 0.617021 (612 2212);
PAINT ORANGE (612 2212);
FORCEPROP 1 LAST MATERIAL CHIP
J 1
(675 2150);
DISPLAY 0.617021 (675 2150);
PAINT SKYBLUE (675 2150);
FORCEPROP 1 LAST PACK_TYPE 0402
J 1
(800 2150);
DISPLAY 0.617021 (800 2150);
PAINT SKYBLUE (800 2150);
FORCEPROP 1 LAST PART_NUMBER G21497-005
J 0
(675 2200);
DISPLAY 0.617021 (675 2200);
PAINT BLUE (675 2200);
FORCEPROP 0 LAST ROOM CLOCK_CPU1_OSC
J 0
(500 2350);
DISPLAY 1.021277 (500 2350);
PAINT ORANGE (500 2350);
DISPLAY INVISIBLE (500 2350);
FORCEPROP 1 LAST PATH I93
J 0
(500 2350);
DISPLAY 0.978723 (500 2350);
PAINT WHITE (500 2350);
DISPLAY INVISIBLE (500 2350);
FORCEPROP 2 LAST SEC 1
J 0
(500 2400);
DISPLAY 0.680851 (500 2400);
PAINT MONO (500 2400);
DISPLAY INVISIBLE (500 2400);
FORCEPROP 2 LAST SEC_TYPE 0402
J 0
(500 2400);
DISPLAY 1.021277 (500 2400);
PAINT ORANGE (500 2400);
DISPLAY INVISIBLE (500 2400);
FORCEPROP 2 LAST CDS_LIB mstr_discrete
J 0
(550 2200);
PAINT ORANGE (550 2200);
DISPLAY INVISIBLE (550 2200);
FORCEADD RES..1
(550 2000);
FORCEPROP 1 LAST VALUE 0.0
J 1
(325 1950);
DISPLAY 0.617021 (325 1950);
PAINT SKYBLUE (325 1950);
FORCEPROP 1 LASTPIN (450 2000) $PN 1
J 0
(462 2012);
DISPLAY 0.617021 (462 2012);
PAINT ORANGE (462 2012);
FORCEPROP 1 LAST WATTAGE 1/16W
J 0
(375 1950);
DISPLAY 0.617021 (375 1950);
PAINT SKYBLUE (375 1950);
FORCEPROP 1 LAST TOLERANCE 5%
J 0
(525 1950);
DISPLAY 0.617021 (525 1950);
PAINT SKYBLUE (525 1950);
FORCEPROP 1 LASTPIN (650 2000) $PN 2
J 0
(612 2012);
DISPLAY 0.617021 (612 2012);
PAINT ORANGE (612 2012);
FORCEPROP 1 LAST MATERIAL EMPTY
J 1
(675 1950);
DISPLAY 0.617021 (675 1950);
PAINT RED (675 1950);
FORCEPROP 1 LAST PACK_TYPE 0402
J 1
(800 1950);
DISPLAY 0.617021 (800 1950);
PAINT SKYBLUE (800 1950);
FORCEPROP 1 LAST PART_NUMBER G21497-005
J 0
(675 2000);
DISPLAY 0.617021 (675 2000);
PAINT BLUE (675 2000);
FORCEPROP 1 LAST LOCATION R7D40
J 0
(500 2050);
DISPLAY 0.617021 (500 2050);
PAINT AQUA (500 2050);
FORCEPROP 2 LAST CDS_LIB mstr_discrete
J 0
(550 2000);
PAINT ORANGE (550 2000);
DISPLAY INVISIBLE (550 2000);
FORCEPROP 1 LAST PATH I94
J 0
(500 2150);
DISPLAY 0.978723 (500 2150);
PAINT WHITE (500 2150);
DISPLAY INVISIBLE (500 2150);
FORCEPROP 2 LAST SEC 1
J 0
(500 2200);
DISPLAY 0.680851 (500 2200);
PAINT MONO (500 2200);
DISPLAY INVISIBLE (500 2200);
FORCEPROP 2 LAST SEC_TYPE 0402
J 0
(500 2200);
DISPLAY 1.021277 (500 2200);
PAINT ORANGE (500 2200);
DISPLAY INVISIBLE (500 2200);
FORCEPROP 2 LAST ROOM CLOCK_CPU1_OSC
J 0
(1025 2100);
DISPLAY 1.021277 (1025 2100);
PAINT ORANGE (1025 2100);
DISPLAY INVISIBLE (1025 2100);
FORCEADD RES..1
(550 1800);
FORCEPROP 1 LAST VALUE 0.0
J 1
(325 1750);
DISPLAY 0.617021 (325 1750);
PAINT SKYBLUE (325 1750);
FORCEPROP 1 LASTPIN (450 1800) $PN 1
J 0
(462 1812);
DISPLAY 0.617021 (462 1812);
PAINT ORANGE (462 1812);
FORCEPROP 1 LAST LOCATION R7D39
J 0
(500 1850);
DISPLAY 0.617021 (500 1850);
PAINT AQUA (500 1850);
FORCEPROP 1 LAST WATTAGE 1/16W
J 0
(375 1750);
DISPLAY 0.617021 (375 1750);
PAINT SKYBLUE (375 1750);
FORCEPROP 1 LAST TOLERANCE 5%
J 0
(525 1750);
DISPLAY 0.617021 (525 1750);
PAINT SKYBLUE (525 1750);
FORCEPROP 1 LAST MATERIAL EMPTY
J 1
(675 1750);
DISPLAY 0.617021 (675 1750);
PAINT RED (675 1750);
FORCEPROP 1 LASTPIN (650 1800) $PN 2
J 0
(612 1812);
DISPLAY 0.617021 (612 1812);
PAINT ORANGE (612 1812);
FORCEPROP 1 LAST PACK_TYPE 0402
J 1
(800 1750);
DISPLAY 0.617021 (800 1750);
PAINT SKYBLUE (800 1750);
FORCEPROP 1 LAST PART_NUMBER G21497-005
J 0
(675 1800);
DISPLAY 0.617021 (675 1800);
PAINT BLUE (675 1800);
FORCEPROP 1 LAST PATH I95
J 0
(500 1950);
DISPLAY 0.978723 (500 1950);
PAINT WHITE (500 1950);
DISPLAY INVISIBLE (500 1950);
FORCEPROP 2 LAST SEC 1
J 0
(500 2000);
DISPLAY 0.680851 (500 2000);
PAINT MONO (500 2000);
DISPLAY INVISIBLE (500 2000);
FORCEPROP 2 LAST SEC_TYPE 0402
J 0
(500 2000);
DISPLAY 1.021277 (500 2000);
PAINT ORANGE (500 2000);
DISPLAY INVISIBLE (500 2000);
FORCEPROP 2 LAST CDS_LIB mstr_discrete
J 0
(550 1800);
PAINT ORANGE (550 1800);
DISPLAY INVISIBLE (550 1800);
FORCEADD RES..1
(550 1500);
FORCEPROP 1 LAST VALUE 0.0
J 1
(325 1450);
DISPLAY 0.617021 (325 1450);
PAINT SKYBLUE (325 1450);
FORCEPROP 1 LASTPIN (450 1500) $PN 1
J 0
(462 1512);
DISPLAY 0.617021 (462 1512);
PAINT ORANGE (462 1512);
FORCEPROP 1 LAST WATTAGE 1/16W
J 0
(375 1450);
DISPLAY 0.617021 (375 1450);
PAINT SKYBLUE (375 1450);
FORCEPROP 1 LAST LOCATION R7D36
J 0
(500 1550);
DISPLAY 0.617021 (500 1550);
PAINT AQUA (500 1550);
FORCEPROP 1 LAST TOLERANCE 5%
J 0
(525 1450);
DISPLAY 0.617021 (525 1450);
PAINT SKYBLUE (525 1450);
FORCEPROP 1 LAST MATERIAL CHIP
J 1
(675 1450);
DISPLAY 0.617021 (675 1450);
PAINT SKYBLUE (675 1450);
FORCEPROP 1 LAST PACK_TYPE 0402
J 1
(800 1450);
DISPLAY 0.617021 (800 1450);
PAINT SKYBLUE (800 1450);
FORCEPROP 1 LAST PART_NUMBER G21497-005
J 0
(675 1500);
DISPLAY 0.617021 (675 1500);
PAINT BLUE (675 1500);
FORCEPROP 1 LASTPIN (650 1500) $PN 2
J 0
(612 1512);
DISPLAY 0.617021 (612 1512);
PAINT ORANGE (612 1512);
FORCEPROP 0 LAST ROOM CLOCK_CPU1_OSC
J 0
(500 1650);
DISPLAY 1.021277 (500 1650);
PAINT ORANGE (500 1650);
DISPLAY INVISIBLE (500 1650);
FORCEPROP 1 LAST PATH I96
J 0
(500 1650);
DISPLAY 0.978723 (500 1650);
PAINT WHITE (500 1650);
DISPLAY INVISIBLE (500 1650);
FORCEPROP 2 LAST SEC 1
J 0
(500 1700);
DISPLAY 0.680851 (500 1700);
PAINT MONO (500 1700);
DISPLAY INVISIBLE (500 1700);
FORCEPROP 2 LAST SEC_TYPE 0402
J 0
(500 1700);
DISPLAY 1.021277 (500 1700);
PAINT ORANGE (500 1700);
DISPLAY INVISIBLE (500 1700);
FORCEPROP 2 LAST CDS_LIB mstr_discrete
J 0
(550 1500);
PAINT ORANGE (550 1500);
DISPLAY INVISIBLE (550 1500);
FORCEADD RES..1
(550 1300);
FORCEPROP 1 LAST VALUE 0.0
J 1
(325 1250);
DISPLAY 0.617021 (325 1250);
PAINT SKYBLUE (325 1250);
FORCEPROP 1 LASTPIN (450 1300) $PN 1
J 0
(462 1312);
DISPLAY 0.617021 (462 1312);
PAINT ORANGE (462 1312);
FORCEPROP 1 LAST WATTAGE 1/16W
J 0
(375 1250);
DISPLAY 0.617021 (375 1250);
PAINT SKYBLUE (375 1250);
FORCEPROP 1 LAST LOCATION R7D38
J 0
(500 1350);
DISPLAY 0.617021 (500 1350);
PAINT AQUA (500 1350);
FORCEPROP 1 LAST TOLERANCE 5%
J 0
(525 1250);
DISPLAY 0.617021 (525 1250);
PAINT SKYBLUE (525 1250);
FORCEPROP 1 LAST MATERIAL EMPTY
J 1
(675 1250);
DISPLAY 0.617021 (675 1250);
PAINT RED (675 1250);
FORCEPROP 1 LASTPIN (650 1300) $PN 2
J 0
(612 1312);
DISPLAY 0.617021 (612 1312);
PAINT ORANGE (612 1312);
FORCEPROP 1 LAST PACK_TYPE 0402
J 1
(800 1250);
DISPLAY 0.617021 (800 1250);
PAINT SKYBLUE (800 1250);
FORCEPROP 1 LAST PART_NUMBER G21497-005
J 0
(675 1300);
DISPLAY 0.617021 (675 1300);
PAINT BLUE (675 1300);
FORCEPROP 1 LAST PATH I97
J 0
(500 1450);
DISPLAY 0.978723 (500 1450);
PAINT WHITE (500 1450);
DISPLAY INVISIBLE (500 1450);
FORCEPROP 2 LAST SEC 1
J 0
(500 1500);
DISPLAY 0.680851 (500 1500);
PAINT MONO (500 1500);
DISPLAY INVISIBLE (500 1500);
FORCEPROP 2 LAST SEC_TYPE 0402
J 0
(500 1500);
DISPLAY 1.021277 (500 1500);
PAINT ORANGE (500 1500);
DISPLAY INVISIBLE (500 1500);
FORCEPROP 2 LAST CDS_LIB mstr_discrete
J 0
(550 1300);
PAINT ORANGE (550 1300);
DISPLAY INVISIBLE (550 1300);
FORCEPROP 2 LAST ROOM CLOCK_CPU1_OSC
J 0
(1025 1400);
DISPLAY 1.021277 (1025 1400);
PAINT ORANGE (1025 1400);
DISPLAY INVISIBLE (1025 1400);
FORCEADD RES..1
(550 1100);
FORCEPROP 1 LAST VALUE 0.0
J 1
(325 1050);
DISPLAY 0.617021 (325 1050);
PAINT SKYBLUE (325 1050);
FORCEPROP 1 LASTPIN (450 1100) $PN 1
J 0
(462 1112);
DISPLAY 0.617021 (462 1112);
PAINT ORANGE (462 1112);
FORCEPROP 1 LAST WATTAGE 1/16W
J 0
(375 1050);
DISPLAY 0.617021 (375 1050);
PAINT SKYBLUE (375 1050);
FORCEPROP 1 LAST LOCATION R7D37
J 0
(500 1150);
DISPLAY 0.617021 (500 1150);
PAINT AQUA (500 1150);
FORCEPROP 1 LAST TOLERANCE 5%
J 0
(525 1050);
DISPLAY 0.617021 (525 1050);
PAINT SKYBLUE (525 1050);
FORCEPROP 1 LASTPIN (650 1100) $PN 2
J 0
(612 1112);
DISPLAY 0.617021 (612 1112);
PAINT ORANGE (612 1112);
FORCEPROP 1 LAST MATERIAL EMPTY
J 1
(675 1050);
DISPLAY 0.617021 (675 1050);
PAINT RED (675 1050);
FORCEPROP 1 LAST PACK_TYPE 0402
J 1
(800 1050);
DISPLAY 0.617021 (800 1050);
PAINT SKYBLUE (800 1050);
FORCEPROP 1 LAST PART_NUMBER G21497-005
J 0
(675 1100);
DISPLAY 0.617021 (675 1100);
PAINT BLUE (675 1100);
FORCEPROP 1 LAST PATH I98
J 0
(500 1250);
DISPLAY 0.978723 (500 1250);
PAINT WHITE (500 1250);
DISPLAY INVISIBLE (500 1250);
FORCEPROP 2 LAST SEC 1
J 0
(500 1300);
DISPLAY 0.680851 (500 1300);
PAINT MONO (500 1300);
DISPLAY INVISIBLE (500 1300);
FORCEPROP 2 LAST SEC_TYPE 0402
J 0
(500 1300);
DISPLAY 1.021277 (500 1300);
PAINT ORANGE (500 1300);
DISPLAY INVISIBLE (500 1300);
FORCEPROP 2 LAST CDS_LIB mstr_discrete
J 0
(550 1100);
PAINT ORANGE (550 1100);
DISPLAY INVISIBLE (550 1100);
FORCEADD OFFPAGE..1
(-525 2200);
FORCEPROP 2 LAST $XR0 190 
J 0
(-777 2200);
DISPLAY 0.638298 (-777 2200);
PAINT MONO (-777 2200);
FORCEPROP 2 LAST CDS_LIB mstr_standard
J 0
(-525 2200);
PAINT ORANGE (-525 2200);
DISPLAY INVISIBLE (-525 2200);
FORCEPROP 2 LAST PATH I99
J 0
(-475 2275);
DISPLAY 1.021277 (-475 2275);
PAINT ORANGE (-475 2275);
DISPLAY INVISIBLE (-475 2275);
FORCEPROP 1 LAST COMMENT_BODY TRUE
J 0
(-400 2100);
DISPLAY 0.872340 (-400 2100);
PAINT GREEN (-400 2100);
DISPLAY INVISIBLE (-400 2100);
FORCEPROP 1 LAST OFFPAGE TRUE
J 0
(-200 2075);
DISPLAY 0.872340 (-200 2075);
PAINT GREEN (-200 2075);
DISPLAY INVISIBLE (-200 2075);
FORCEADD DNS..2
(530 4945);
PAINT RED (530 4945);
FORCEPROP 1 LAST COMMENT_BODY TRUE
R 1
J 0
(605 4720);
DISPLAY 0.872340 (605 4720);
PAINT GREEN (605 4720);
DISPLAY INVISIBLE (605 4720);
FORCEPROP 2 LAST CDS_LIB mstr_misc
J 0
(530 4945);
PAINT ORANGE (530 4945);
DISPLAY INVISIBLE (530 4945);
FORCEADD DNS..2
(555 1095);
PAINT RED (555 1095);
FORCEPROP 1 LAST COMMENT_BODY TRUE
R 1
J 0
(630 870);
DISPLAY 0.872340 (630 870);
PAINT GREEN (630 870);
DISPLAY INVISIBLE (630 870);
FORCEPROP 2 LAST CDS_LIB mstr_misc
J 0
(555 1095);
PAINT ORANGE (555 1095);
DISPLAY INVISIBLE (555 1095);
FORCEADD CAD_NOTE..1
(-1350 2625);
FORCEPROP 0 LAST L1 USE A COMMON FOOTPRINT FOR RESISTORS
J 0
(-1475 2475);
DISPLAY 1.021277 (-1475 2475);
PAINT ORANGE (-1475 2475);
FORCEPROP 1 LAST COMMENT_BODY TRUE
J 0
(-1325 2725);
DISPLAY 0.978723 (-1325 2725);
PAINT ORANGE (-1325 2725);
DISPLAY INVISIBLE (-1325 2725);
FORCEPROP 2 LAST CDS_LIB mstr_symbols
J 0
(-1350 2625);
PAINT ORANGE (-1350 2625);
DISPLAY INVISIBLE (-1350 2625);
FORCEADD DNS..2
(530 2870);
PAINT RED (530 2870);
FORCEPROP 1 LAST COMMENT_BODY TRUE
R 1
J 0
(605 2645);
DISPLAY 0.872340 (605 2645);
PAINT GREEN (605 2645);
DISPLAY INVISIBLE (605 2645);
FORCEPROP 2 LAST CDS_LIB mstr_misc
J 0
(530 2870);
PAINT ORANGE (530 2870);
DISPLAY INVISIBLE (530 2870);
FORCEADD DNS..2
(530 4745);
PAINT RED (530 4745);
FORCEPROP 1 LAST COMMENT_BODY TRUE
R 1
J 0
(605 4520);
DISPLAY 0.872340 (605 4520);
PAINT GREEN (605 4520);
DISPLAY INVISIBLE (605 4520);
FORCEPROP 2 LAST CDS_LIB mstr_misc
J 0
(530 4745);
PAINT ORANGE (530 4745);
DISPLAY INVISIBLE (530 4745);
FORCEADD DNS..2
(530 4095);
PAINT RED (530 4095);
FORCEPROP 1 LAST COMMENT_BODY TRUE
R 1
J 0
(605 3870);
DISPLAY 0.872340 (605 3870);
PAINT GREEN (605 3870);
DISPLAY INVISIBLE (605 3870);
FORCEPROP 2 LAST CDS_LIB mstr_misc
J 0
(530 4095);
PAINT ORANGE (530 4095);
DISPLAY INVISIBLE (530 4095);
FORCEADD DNS..2
(530 3370);
PAINT RED (530 3370);
FORCEPROP 1 LAST COMMENT_BODY TRUE
R 1
J 0
(605 3145);
DISPLAY 0.872340 (605 3145);
PAINT GREEN (605 3145);
DISPLAY INVISIBLE (605 3145);
FORCEPROP 2 LAST CDS_LIB mstr_misc
J 0
(530 3370);
PAINT ORANGE (530 3370);
DISPLAY INVISIBLE (530 3370);
FORCEADD DNS..2
(530 2670);
PAINT RED (530 2670);
FORCEPROP 1 LAST COMMENT_BODY TRUE
R 1
J 0
(605 2445);
DISPLAY 0.872340 (605 2445);
PAINT GREEN (605 2445);
DISPLAY INVISIBLE (605 2445);
FORCEPROP 2 LAST CDS_LIB mstr_misc
J 0
(530 2670);
PAINT ORANGE (530 2670);
DISPLAY INVISIBLE (530 2670);
FORCEADD DNS..2
(555 1995);
PAINT RED (555 1995);
FORCEPROP 1 LAST COMMENT_BODY TRUE
R 1
J 0
(630 1770);
DISPLAY 0.872340 (630 1770);
PAINT GREEN (630 1770);
DISPLAY INVISIBLE (630 1770);
FORCEPROP 2 LAST CDS_LIB mstr_misc
J 0
(555 1995);
PAINT ORANGE (555 1995);
DISPLAY INVISIBLE (555 1995);
FORCEADD DNS..2
(555 1795);
PAINT RED (555 1795);
FORCEPROP 1 LAST COMMENT_BODY TRUE
R 1
J 0
(630 1570);
DISPLAY 0.872340 (630 1570);
PAINT GREEN (630 1570);
DISPLAY INVISIBLE (630 1570);
FORCEPROP 2 LAST CDS_LIB mstr_misc
J 0
(555 1795);
PAINT ORANGE (555 1795);
DISPLAY INVISIBLE (555 1795);
FORCEADD DNS..2
(555 1295);
PAINT RED (555 1295);
FORCEPROP 1 LAST COMMENT_BODY TRUE
R 1
J 0
(630 1070);
DISPLAY 0.872340 (630 1070);
PAINT GREEN (630 1070);
DISPLAY INVISIBLE (630 1070);
FORCEPROP 2 LAST CDS_LIB mstr_misc
J 0
(555 1295);
PAINT ORANGE (555 1295);
DISPLAY INVISIBLE (555 1295);
FORCEADD DNS..2
(530 4295);
PAINT RED (530 4295);
FORCEPROP 1 LAST COMMENT_BODY TRUE
R 1
J 0
(605 4070);
DISPLAY 0.872340 (605 4070);
PAINT GREEN (605 4070);
DISPLAY INVISIBLE (605 4070);
FORCEPROP 2 LAST CDS_LIB mstr_misc
J 0
(530 4295);
PAINT ORANGE (530 4295);
DISPLAY INVISIBLE (530 4295);
FORCEADD DNS..2
(530 3570);
PAINT RED (530 3570);
FORCEPROP 1 LAST COMMENT_BODY TRUE
R 1
J 0
(605 3345);
DISPLAY 0.872340 (605 3345);
PAINT GREEN (605 3345);
DISPLAY INVISIBLE (605 3345);
FORCEPROP 2 LAST CDS_LIB mstr_misc
J 0
(530 3570);
PAINT ORANGE (530 3570);
DISPLAY INVISIBLE (530 3570);
FORCEADD INTEL_CORP_BPAGE..1
(2650 500);
FORCEPROP 1 LAST CDS_CON_LAST_MODIFIED Tue Dec 01 11:51:52 2015
J 0
(1225 825);
DISPLAY 0.617021 (1225 825);
PAINT ORANGE (1225 825);
DISPLAY INVISIBLE (1225 825);
FORCEPROP 1 LAST CUSTOM_TXT_CDS <CURRENT_DESIGN_SHEET> OF <TOTAL_DESIGN_SHEETS>
J 0
(2150 525);
PAINT GREEN (2150 525);
FORCEPROP 1 LAST CUSTOM_TXT_CDS <CON_LAST_MODIFIED>
J 0
(725 850);
PAINT GREEN (725 850);
FORCEPROP 2 LAST CUSTOM_TXT_CDS <XR_PAGE_TITLE>
J 0
(-5240 5750);
DISPLAY 0.638298 (-5240 5750);
PAINT PINK (-5240 5750);
DISPLAY INVISIBLE (-5240 5750);
FORCEPROP 1 LAST SCH_TITLE HFI OSCILLATORS
J 0
(-5300 550);
DISPLAY 1.212766 (-5300 550);
PAINT GREEN (-5300 550);
FORCEPROP 1 LAST SCH_ADDRESS1 2200 Mission College Blvd.
J 0
(-1325 625);
DISPLAY 0.617021 (-1325 625);
PAINT GREEN (-1325 625);
FORCEPROP 1 LAST SCH_ADDRESS2 P.O. BOX 58119
J 0
(-1325 575);
DISPLAY 0.617021 (-1325 575);
PAINT GREEN (-1325 575);
FORCEPROP 1 LAST SCH_ADDRESS3 Santa Clara, CA 95052-8119
J 0
(-1325 525);
DISPLAY 0.617021 (-1325 525);
PAINT GREEN (-1325 525);
FORCEPROP 1 LAST SCH_NUMBER H4694802
J 0
(1350 650);
DISPLAY 1.212766 (1350 650);
PAINT YELLOW (1350 650);
FORCEPROP 1 LAST SCH_DEPT BESD
J 1
(-1800 600);
DISPLAY 1.212766 (-1800 600);
PAINT YELLOW (-1800 600);
FORCEPROP 1 LAST SCH_REV 2.420
J 0
(2400 650);
DISPLAY 0.978723 (2400 650);
PAINT YELLOW (2400 650);
FORCEPROP 2 LAST PAGE_BORDER TRUE
J 0
(-5240 5750);
DISPLAY 0.531915 (-5240 5750);
PAINT PINK (-5240 5750);
DISPLAY INVISIBLE (-5240 5750);
FORCEPROP 1 LAST COMMENT_BODY TRUE
J 0
(2660 510);
DISPLAY 0.297872 (2660 510);
PAINT GREEN (2660 510);
DISPLAY INVISIBLE (2660 510);
FORCEPROP 2 LAST CDS_LIB mstr_symbols
J 0
(2650 500);
DISPLAY 0.617021 (2650 500);
PAINT MONO (2650 500);
DISPLAY INVISIBLE (2650 500);
FORCEPROP 2 LAST CDS_XR_PAGE_TITLE CR-104 : @BASEBOARD_FAB2_LIB.BASEBOARD_FAB2(SCH_1):PAGE104
J 0
(-5240 5750);
DISPLAY 0.638298 (-5240 5750);
PAINT PINK (-5240 5750);
DISPLAY INVISIBLE (-5240 5750);
WIRE 16 -1 (-4250 5200)(-4250 5250);
WIRE 16 -1 (-4250 5250)(-3975 5250);
WIRE 16 -1 (-3975 4875)(-3975 5250);
WIRE 16 -1 (-3975 5250)(-3975 5300);
WIRE 16 -1 (-3900 4875)(-3975 4875);
WIRE 16 -1 (-2900 4675)(-2725 4675);
WIRE 16 -1 (-2725 4675)(-2725 4600);
WIRE 16 -1 (-4250 5000)(-4250 4950);
WIRE 16 -1 (-3200 3825)(-3050 3825);
WIRE 16 -1 (-3050 3825)(-3050 3750);
WIRE 16 -1 (-4575 4325)(-4575 4375);
WIRE 16 -1 (-4575 4375)(-4275 4375);
WIRE 16 -1 (-4275 4025)(-4275 4375);
WIRE 16 -1 (-4275 4375)(-4275 4425);
WIRE 16 -1 (-4200 4025)(-4275 4025);
WIRE 16 -1 (-4575 4125)(-4575 4075);
WIRE 16 -1 (950 4500)(1625 4500);
FORCEPROP 2 LAST SIG_NAME CLK_156M_OSC_CPU0_HFI_DP
J 0
(1000 4510);
DISPLAY 0.617021 (1000 4510);
PAINT ORANGE (1000 4510);
WIRE 16 -1 (950 4300)(950 4500);
WIRE 16 -1 (625 4500)(950 4500);
WIRE 16 -1 (625 4300)(950 4300);
WIRE 16 -1 (625 4750)(1625 4750);
FORCEPROP 2 LAST SIG_NAME CLK_322M_OSC_CPU0_RC_DN
J 0
(1000 4760);
DISPLAY 0.617021 (1000 4760);
PAINT ORANGE (1000 4760);
WIRE 16 -1 (625 4100)(1625 4100);
FORCEPROP 2 LAST SIG_NAME CLK_322M_OSC_CPU0_RC_DP
J 0
(1000 4110);
DISPLAY 0.617021 (1000 4110);
PAINT ORANGE (1000 4110);
WIRE 16 -1 (625 5150)(950 5150);
WIRE 16 -1 (1625 5150)(950 5150);
FORCEPROP 2 LAST SIG_NAME CLK_156M_OSC_CPU0_HFI_DN
J 0
(1000 5160);
DISPLAY 0.617021 (1000 5160);
PAINT ORANGE (1000 5160);
WIRE 16 -1 (950 4950)(950 5150);
WIRE 16 -1 (625 4950)(950 4950);
WIRE 16 -1 (75 4750)(425 4750);
WIRE 16 -1 (75 4950)(75 4750);
WIRE 16 -1 (75 4950)(425 4950);
WIRE 16 -1 (-500 4950)(75 4950);
FORCEPROP 2 LAST SIG_NAME CLK_322M_156M_CPU0_OSC_VRM_DN
J 0
(-500 4960);
DISPLAY 0.617021 (-500 4960);
PAINT ORANGE (-500 4960);
WIRE 16 -1 (75 4100)(425 4100);
WIRE 16 -1 (75 4300)(75 4100);
WIRE 16 -1 (425 4300)(75 4300);
WIRE 16 -1 (75 4300)(-500 4300);
FORCEPROP 2 LAST SIG_NAME CLK_322M_156M_CPU0_OSC_VRM_DP
J 0
(-500 4310);
DISPLAY 0.617021 (-500 4310);
PAINT ORANGE (-500 4310);
WIRE 16 682 (2525 925)(2525 5425);
WIRE 16 682 (-1600 925)(2525 925);
WIRE 16 682 (2525 5425)(-1600 5425);
WIRE 16 682 (-1600 5425)(-1600 925);
WIRE 16 -1 (625 3775)(950 3775);
WIRE 16 -1 (950 3775)(1625 3775);
FORCEPROP 2 LAST SIG_NAME CLK_156M_OSC_CPU1_HFI_DN
J 0
(1000 3785);
DISPLAY 0.617021 (1000 3785);
PAINT ORANGE (1000 3785);
WIRE 16 -1 (950 3575)(950 3775);
WIRE 16 -1 (625 3575)(950 3575);
WIRE 16 -1 (625 3075)(950 3075);
WIRE 16 -1 (950 3075)(1625 3075);
FORCEPROP 2 LAST SIG_NAME CLK_156M_OSC_CPU1_HFI_DP
J 0
(1000 3085);
DISPLAY 0.617021 (1000 3085);
PAINT ORANGE (1000 3085);
WIRE 16 -1 (950 2875)(950 3075);
WIRE 16 -1 (625 2875)(950 2875);
WIRE 16 -1 (650 2200)(975 2200);
WIRE 16 -1 (975 2200)(1650 2200);
FORCEPROP 2 LAST SIG_NAME FM_CPU0_STL_BRD_OSC_EN
J 0
(1000 2210);
DISPLAY 0.617021 (1000 2210);
PAINT ORANGE (1000 2210);
WIRE 16 -1 (975 2000)(975 2200);
WIRE 16 -1 (650 2000)(975 2000);
WIRE 16 -1 (625 3375)(1625 3375);
FORCEPROP 2 LAST SIG_NAME CLK_322M_OSC_CPU1_RC_DN
J 0
(1000 3385);
DISPLAY 0.617021 (1000 3385);
PAINT ORANGE (1000 3385);
WIRE 16 -1 (625 2675)(1625 2675);
FORCEPROP 2 LAST SIG_NAME CLK_322M_OSC_CPU1_RC_DP
J 0
(1000 2685);
DISPLAY 0.617021 (1000 2685);
PAINT ORANGE (1000 2685);
WIRE 16 -1 (75 3375)(425 3375);
WIRE 16 -1 (75 3575)(75 3375);
WIRE 16 -1 (75 3575)(425 3575);
WIRE 16 -1 (-500 3575)(75 3575);
FORCEPROP 0 LAST SIG_NAME CLK_322M_156M_CPU1_OSC_VRM_DN
J 0
(-500 3585);
DISPLAY 0.617021 (-500 3585);
PAINT ORANGE (-500 3585);
WIRE 16 -1 (75 2675)(425 2675);
WIRE 16 -1 (75 2875)(75 2675);
WIRE 16 -1 (75 2875)(425 2875);
WIRE 16 -1 (-500 2875)(75 2875);
FORCEPROP 0 LAST SIG_NAME CLK_322M_156M_CPU1_OSC_VRM_DP
J 0
(-500 2885);
DISPLAY 0.617021 (-500 2885);
PAINT ORANGE (-500 2885);
WIRE 16 -1 (975 1500)(1650 1500);
FORCEPROP 2 LAST SIG_NAME FM_CPU1_STL_BRD_OSC_EN
J 0
(1000 1510);
DISPLAY 0.617021 (1000 1510);
PAINT ORANGE (1000 1510);
WIRE 16 -1 (975 1300)(975 1500);
WIRE 16 -1 (650 1500)(975 1500);
WIRE 16 -1 (650 1300)(975 1300);
WIRE 16 -1 (650 1100)(1650 1100);
FORCEPROP 2 LAST SIG_NAME FM_CPU1_VRM_322M_156M_OSC_EN
J 0
(1000 1110);
DISPLAY 0.617021 (1000 1110);
PAINT ORANGE (1000 1110);
WIRE 16 -1 (650 1800)(1650 1800);
FORCEPROP 2 LAST SIG_NAME FM_CPU0_VRM_322M_156M_OSC_EN
J 0
(1000 1810);
DISPLAY 0.617021 (1000 1810);
PAINT ORANGE (1000 1810);
WIRE 16 -1 (100 2000)(450 2000);
WIRE 16 -1 (100 2000)(100 1800);
WIRE 16 -1 (-475 2000)(100 2000);
FORCEPROP 2 LAST SIG_NAME FM_CPU0_VRM_OSC_EN
J 0
(-460 2010);
DISPLAY 0.617021 (-460 2010);
PAINT ORANGE (-460 2010);
WIRE 16 -1 (100 1800)(450 1800);
WIRE 16 -1 (100 1300)(450 1300);
WIRE 16 -1 (100 1300)(100 1100);
WIRE 16 -1 (-475 1300)(100 1300);
FORCEPROP 2 LAST SIG_NAME FM_CPU1_VRM_OSC_EN
J 0
(-460 1310);
DISPLAY 0.617021 (-460 1310);
PAINT ORANGE (-460 1310);
WIRE 16 -1 (100 1100)(450 1100);
WIRE 16 -1 (-500 3075)(425 3075);
FORCEPROP 2 LAST SIG_NAME CLK_156M_OSC_BRD_CPU1_DP
J 0
(-500 3085);
DISPLAY 0.617021 (-500 3085);
PAINT ORANGE (-500 3085);
WIRE 16 -1 (425 4500)(-500 4500);
FORCEPROP 2 LAST SIG_NAME CLK_156M_OSC_BRD_CPU0_DP
J 0
(-500 4510);
DISPLAY 0.617021 (-500 4510);
PAINT ORANGE (-500 4510);
WIRE 16 -1 (-475 1500)(450 1500);
FORCEPROP 2 LAST SIG_NAME FM_156M_CPU1_BRD_OSC_EN
J 0
(-460 1510);
DISPLAY 0.617021 (-460 1510);
PAINT ORANGE (-460 1510);
WIRE 16 -1 (-500 3775)(425 3775);
FORCEPROP 0 LAST SIG_NAME CLK_156M_OSC_BRD_CPU1_DN
J 0
(-500 3785);
DISPLAY 0.617021 (-500 3785);
PAINT ORANGE (-500 3785);
WIRE 16 -1 (-475 2200)(450 2200);
FORCEPROP 2 LAST SIG_NAME FM_156M_CPU0_BRD_OSC_EN
J 0
(-435 2210);
DISPLAY 0.617021 (-435 2210);
PAINT ORANGE (-435 2210);
WIRE 16 -1 (425 5150)(-500 5150);
FORCEPROP 2 LAST SIG_NAME CLK_156M_OSC_BRD_CPU0_DN
J 0
(-500 5160);
DISPLAY 0.617021 (-500 5160);
PAINT ORANGE (-500 5160);
WIRE 16 -1 (-2900 4875)(-2200 4875);
FORCEPROP 2 LAST SIG_NAME CLK_156M_OSC_BRD_CPU0_DN
J 0
(-2810 4885);
DISPLAY 0.617021 (-2810 4885);
PAINT ORANGE (-2810 4885);
WIRE 16 -1 (-2900 4775)(-2200 4775);
FORCEPROP 2 LAST SIG_NAME CLK_156M_OSC_BRD_CPU0_DP
J 0
(-2810 4785);
DISPLAY 0.617021 (-2810 4785);
PAINT ORANGE (-2810 4785);
WIRE 16 -1 (-3200 4025)(-2500 4025);
FORCEPROP 2 LAST SIG_NAME CLK_156M_OSC_BRD_CPU1_DN
J 0
(-3060 4035);
DISPLAY 0.617021 (-3060 4035);
PAINT ORANGE (-3060 4035);
WIRE 16 -1 (-3200 3925)(-2500 3925);
FORCEPROP 2 LAST SIG_NAME CLK_156M_OSC_BRD_CPU1_DP
J 0
(-3060 3935);
DISPLAY 0.617021 (-3060 3935);
PAINT ORANGE (-3060 3935);
WIRE 16 -1 (-4275 825)(-2350 825);
WIRE 16 -1 (-4275 925)(-4275 825);
WIRE 16 -1 (-4275 825)(-4275 725);
WIRE 16 -1 (-2350 925)(-2350 825);
WIRE 16 -1 (-2350 825)(-2350 725);
WIRE 16 -1 (-4275 725)(-2350 725);
WIRE 16 -1 (-2350 725)(-2350 625);
WIRE 16 -1 (-2900 925)(-2350 925);
WIRE 16 -1 (-4275 725)(-4275 625);
WIRE 16 -1 (-3850 925)(-4275 925);
WIRE 16 -1 (-3375 925)(-3850 925);
WIRE 16 -1 (-3850 925)(-3850 625);
WIRE 16 -1 (-4275 625)(-3850 625);
WIRE 16 -1 (-2900 925)(-2900 625);
WIRE 16 -1 (-3375 925)(-2900 925);
WIRE 16 -1 (-2900 625)(-2350 625);
WIRE 16 -1 (-3375 625)(-2900 625);
WIRE 16 -1 (-3375 925)(-3375 625);
WIRE 16 -1 (-3850 625)(-3375 625);
WIRE 16 -1 (-4475 4775)(-3900 4775);
FORCEPROP 2 LAST SIG_NAME FM_CPU0_STL_BRD_OSC_EN
J 0
(-4475 4785);
DISPLAY 0.617021 (-4475 4785);
PAINT ORANGE (-4475 4785);
WIRE 16 -1 (-4475 4675)(-3900 4675);
FORCEPROP 0 LAST SIG_NAME NC_CLK_156M_CPU0_OSC
J 0
(-4475 4685);
DISPLAY 0.617021 (-4475 4685);
PAINT ORANGE (-4475 4685);
FORCEPROP 2 LASTPROP $XRERR UNIQUE?
J 0
(-4715 4675);
DISPLAY 0.638298 (-4715 4675);
PAINT MONO (-4715 4675);
DISPLAY INVISIBLE (-4715 4675);
WIRE 16 -1 (-4800 3925)(-4200 3925);
FORCEPROP 2 LAST SIG_NAME FM_CPU1_STL_BRD_OSC_EN
J 0
(-4800 3935);
DISPLAY 0.617021 (-4800 3935);
PAINT ORANGE (-4800 3935);
WIRE 16 -1 (-4800 3825)(-4200 3825);
FORCEPROP 2 LAST SIG_NAME NC_CLK_156M_CPU1_OSC
J 0
(-4800 3835);
DISPLAY 0.617021 (-4800 3835);
PAINT ORANGE (-4800 3835);
FORCEPROP 2 LASTPROP $XRERR UNIQUE?
J 0
(-5040 3825);
DISPLAY 0.638298 (-5040 3825);
PAINT MONO (-5040 3825);
DISPLAY INVISIBLE (-5040 3825);
DOT 1 (950 5150);
DOT 1 (950 4500);
DOT 1 (75 4950);
DOT 1 (75 4300);
DOT 1 (950 3775);
DOT 1 (75 3575);
DOT 1 (950 3075);
DOT 1 (975 2200);
DOT 1 (75 2875);
DOT 1 (975 1500);
DOT 1 (100 2000);
DOT 1 (100 1300);
DOT 1 (-3975 5250);
DOT 1 (-2350 825);
DOT 1 (-2350 725);
DOT 1 (-2900 925);
DOT 1 (-2900 625);
DOT 1 (-3375 925);
DOT 1 (-3375 625);
DOT 1 (-3850 925);
DOT 1 (-3850 625);
DOT 1 (-4275 4375);
DOT 1 (-4275 825);
DOT 1 (-4275 725);
FORCENOTE
$CDS_IMAGE|OSC_VRM_topology_0.JPG|2518|2000
(-3600 2225) 0;
DISPLAY CENTER (-3600 2225);
PAINT MONO (-3600 2225);
FORCENOTE
SKX OR SKX MCP STEERING OPTIONS
(-250 5275) 0;
DISPLAY LEFT (-250 5275);
DISPLAY 1.595745 (-250 5275);
PAINT PURPLE (-250 5275);
FORCENOTE
CPU0 MCP
(1700 4650) 0;
DISPLAY LEFT (1700 4650);
DISPLAY 0.808511 (1700 4650);
PAINT PURPLE (1700 4650);
FORCENOTE
CPU0 STL
(1700 5025) 0;
DISPLAY LEFT (1700 5025);
DISPLAY 0.808511 (1700 5025);
PAINT PURPLE (1700 5025);
FORCENOTE
CPU0 STL
(1700 4375) 0;
DISPLAY LEFT (1700 4375);
DISPLAY 0.808511 (1700 4375);
PAINT PURPLE (1700 4375);
FORCENOTE
CPU0 VRM
(1750 1675) 0;
DISPLAY LEFT (1750 1675);
DISPLAY 0.808511 (1750 1675);
PAINT PURPLE (1750 1675);
FORCENOTE
CPU1 VRM
(1750 975) 0;
DISPLAY LEFT (1750 975);
DISPLAY 0.808511 (1750 975);
PAINT PURPLE (1750 975);
FORCENOTE
ON-BOARD CPU1 STL OSC
(1725 1400) 0;
DISPLAY LEFT (1725 1400);
DISPLAY 0.808511 (1725 1400);
PAINT PURPLE (1725 1400);
FORCENOTE
ON-BOARD CPU0 STL OSC
(1700 2100) 0;
DISPLAY LEFT (1700 2100);
DISPLAY 0.808511 (1700 2100);
PAINT PURPLE (1700 2100);
FORCENOTE
CPU1 STL
(1700 3650) 0;
DISPLAY LEFT (1700 3650);
DISPLAY 0.808511 (1700 3650);
PAINT PURPLE (1700 3650);
FORCENOTE
CPU0 MCP
(1700 4000) 0;
DISPLAY LEFT (1700 4000);
DISPLAY 0.808511 (1700 4000);
PAINT PURPLE (1700 4000);
FORCENOTE
CPU1 MCP
(1700 3275) 0;
DISPLAY LEFT (1700 3275);
DISPLAY 0.808511 (1700 3275);
PAINT PURPLE (1700 3275);
FORCENOTE
CPU1 STL
(1700 2950) 0;
DISPLAY LEFT (1700 2950);
DISPLAY 0.808511 (1700 2950);
PAINT PURPLE (1700 2950);
FORCENOTE
CPU1 MCP
(1700 2575) 0;
DISPLAY LEFT (1700 2575);
DISPLAY 0.808511 (1700 2575);
PAINT PURPLE (1700 2575);
FORCENOTE
ENABLE SIGNALS
(250 2350) 0;
DISPLAY LEFT (250 2350);
DISPLAY 1.276596 (250 2350);
PAINT PURPLE (250 2350);
FORCENOTE
ON-BOARD CPU1 STL OSC
(-525 3700) 0;
DISPLAY LEFT (-525 3700);
DISPLAY 0.808511 (-525 3700);
PAINT PURPLE (-525 3700);
FORCENOTE
CPLD CPU0 STL OSC EN
(-500 2125) 0;
DISPLAY LEFT (-500 2125);
DISPLAY 0.808511 (-500 2125);
PAINT PURPLE (-500 2125);
FORCENOTE
CPLD CPU0 MCP OSC EN
(-500 1925) 0;
DISPLAY LEFT (-500 1925);
DISPLAY 0.808511 (-500 1925);
PAINT PURPLE (-500 1925);
FORCENOTE
CPLD CPU1 STL OSC EN
(-500 1425) 0;
DISPLAY LEFT (-500 1425);
DISPLAY 0.808511 (-500 1425);
PAINT PURPLE (-500 1425);
FORCENOTE
CPLD CPU1 MCP OSC EN
(-500 1225) 0;
DISPLAY LEFT (-500 1225);
DISPLAY 0.808511 (-500 1225);
PAINT PURPLE (-500 1225);
FORCENOTE
ON-BOARD CPU0 STL OSC
(-475 5075) 0;
DISPLAY LEFT (-475 5075);
DISPLAY 0.808511 (-475 5075);
PAINT PURPLE (-475 5075);
FORCENOTE
ON-BOARD CPU0 STL OSC
(-525 4425) 0;
DISPLAY LEFT (-525 4425);
DISPLAY 0.808511 (-525 4425);
PAINT PURPLE (-525 4425);
FORCENOTE
ON-BOARD CPU1 STL OSC
(-500 3000) 0;
DISPLAY LEFT (-500 3000);
DISPLAY 0.808511 (-500 3000);
PAINT PURPLE (-500 3000);
FORCENOTE
CPU0 VRM
(-475 4850) 0;
DISPLAY LEFT (-475 4850);
DISPLAY 0.808511 (-475 4850);
PAINT PURPLE (-475 4850);
FORCENOTE
CPU0 VRM
(-475 4200) 0;
DISPLAY LEFT (-475 4200);
DISPLAY 0.808511 (-475 4200);
PAINT PURPLE (-475 4200);
FORCENOTE
ROOM=CLOCK_CPU0_OSC
(-3700 4400) 0;
DISPLAY LEFT (-3700 4400);
DISPLAY 1.021277 (-3700 4400);
PAINT PURPLE (-3700 4400);
FORCENOTE
CPU1 VRM
(-500 3500) 0;
DISPLAY LEFT (-500 3500);
DISPLAY 0.808511 (-500 3500);
PAINT PURPLE (-500 3500);
FORCENOTE
CPU1 VRM
(-500 2800) 0;
DISPLAY LEFT (-500 2800);
DISPLAY 0.808511 (-500 2800);
PAINT PURPLE (-500 2800);
FORCENOTE
FROM CPLD
(-925 1700) 0;
DISPLAY LEFT (-925 1700);
DISPLAY 1.021277 (-925 1700);
PAINT PURPLE (-925 1700);
FORCENOTE
ROOM=CLOCK_CPU1_OSC
(-4075 3475) 0;
DISPLAY LEFT (-4075 3475);
DISPLAY 1.021277 (-4075 3475);
PAINT PURPLE (-4075 3475);
FORCENOTE
DEBUG ONLY
(-2850 650) 0;
DISPLAY LEFT (-2850 650);
DISPLAY 1.021277 (-2850 650);
PAINT PURPLE (-2850 650);
FORCENOTE
COMMENTS
(-2850 850) 0;
DISPLAY LEFT (-2850 850);
DISPLAY 1.021277 (-2850 850);
PAINT PURPLE (-2850 850);
FORCENOTE
N/A
(-2850 750) 0;
DISPLAY LEFT (-2850 750);
DISPLAY 1.021277 (-2850 750);
PAINT PURPLE (-2850 750);
FORCENOTE
H77101-001
(-3300 650) 0;
DISPLAY LEFT (-3300 650);
DISPLAY 1.021277 (-3300 650);
PAINT PURPLE (-3300 650);
FORCENOTE
OSC IPN
(-3300 850) 0;
DISPLAY LEFT (-3300 850);
DISPLAY 1.021277 (-3300 850);
PAINT PURPLE (-3300 850);
FORCENOTE
G63831-004
(-3300 750) 0;
DISPLAY LEFT (-3300 750);
DISPLAY 1.021277 (-3300 750);
PAINT PURPLE (-3300 750);
FORCENOTE
156MHZ
(-3800 750) 0;
DISPLAY LEFT (-3800 750);
DISPLAY 1.021277 (-3800 750);
PAINT PURPLE (-3800 750);
FORCENOTE
FREQUENCY
(-3800 850) 0;
DISPLAY LEFT (-3800 850);
DISPLAY 1.021277 (-3800 850);
PAINT PURPLE (-3800 850);
FORCENOTE
322MHZ
(-3800 650) 0;
DISPLAY LEFT (-3800 650);
DISPLAY 1.021277 (-3800 650);
PAINT PURPLE (-3800 650);
FORCENOTE
CPU
(-4150 850) 0;
DISPLAY LEFT (-4150 850);
DISPLAY 1.021277 (-4150 850);
PAINT PURPLE (-4150 850);
FORCENOTE
SKX
(-4150 750) 0;
DISPLAY LEFT (-4150 750);
DISPLAY 1.021277 (-4150 750);
PAINT PURPLE (-4150 750);
FORCENOTE
SKX MCP
(-4150 650) 0;
DISPLAY LEFT (-4150 650);
DISPLAY 1.021277 (-4150 650);
PAINT PURPLE (-4150 650);
FORCENOTE
OSC CHOICE BASED ON CPU
(-4175 950) 0;
DISPLAY LEFT (-4175 950);
DISPLAY 1.276596 (-4175 950);
PAINT PURPLE (-4175 950);
QUIT
